G04 ================== begin FILE IDENTIFICATION RECORD ==================*
G04 Layout Name:  D:/<user>/Wistron_project/16316-1/gbr-0621/16316-1.brd*
G04 Film Name:    DRILL*
G04 File Format:  Gerber RS274X*
G04 File Origin:  Cadence Allegro 16.5-S056*
G04 Origin Date:  Wed Jun 21 09:31:42 2017*
G04 *
G04 Layer:  MANUFACTURING/NCLEGEND-1-8*
G04 Layer:  MANUFACTURING/DRILL SIZE*
G04 Layer:  DRAWING FORMAT/LAYER_PCB_STORY*
G04 Layer:  DRAWING FORMAT/LAYER_DRILL*
G04 Layer:  BOARD GEOMETRY/PANEL_OUTLINE*
G04 *
G04 Offset:    (0.00 0.00)*
G04 Mirror:    No*
G04 Mode:      Positive*
G04 Rotation:  0*
G04 FullContactRelief:  No*
G04 UndefLineWidth:     6.00*
G04 ================== end FILE IDENTIFICATION RECORD ====================*
%FSLAX35Y35*MOIN*%
%IR0*IPPOS*OFA0.00000B0.00000*MIA0B0*SFA1.00000B1.00000*%
%AMMACRO29*
1,1,.006,0.0,.00728*
20,1,.006,0.0,.00728,.00728,-.00728,0.0*
1,1,.006,.00728,-.00728*
20,1,.006,.00728,-.00728,-.00728,-.00728,0.0*
1,1,.006,-.00728,-.00728*
20,1,.006,-.00728,-.00728,0.0,.00728,0.0*
1,1,.006,0.0,.00728*
1,1,.006,-.00024,-.00364*
20,1,.006,-.00024,-.00364,0.0,-.00206,0.0*
1,1,.006,0.0,-.00206*
20,1,.006,0.0,-.00206,.00036,-.00073,0.0*
1,1,.006,.00036,-.00073*
20,1,.006,.00036,-.00073,.00085,.00049,0.0*
1,1,.006,.00085,.00049*
20,1,.006,.00085,.00049,.00146,.00182,0.0*
1,1,.006,.00146,.00182*
20,1,.006,.00146,.00182,.00243,.00364,0.0*
1,1,.006,.00243,.00364*
20,1,.006,.00243,.00364,-.00243,.00364,0.0*
1,1,.006,-.00243,.00364*
%
%ADD29MACRO29*%
%AMMACRO12*
1,1,.006,.005,.005*
20,1,.006,.005,.005,.005,-.005,0.0*
1,1,.006,.005,-.005*
20,1,.006,.005,-.005,-.005,-.005,0.0*
1,1,.006,-.005,-.005*
20,1,.006,-.005,-.005,-.005,.005,0.0*
1,1,.006,-.005,.005*
20,1,.006,-.005,.005,.005,.005,0.0*
1,1,.006,.005,.005*
1,1,.006,-.00158,.00167*
20,1,.006,-.00158,.00167,-.00108,.00217,0.0*
1,1,.006,-.00108,.00217*
20,1,.006,-.00108,.00217,-.0005,.00242,0.0*
1,1,.006,-.0005,.00242*
20,1,.006,-.0005,.00242,.00017,.0025,0.0*
1,1,.006,.00017,.0025*
20,1,.006,.00017,.0025,.001,.00233,0.0*
1,1,.006,.001,.00233*
20,1,.006,.001,.00233,.00158,.00192,0.0*
1,1,.006,.00158,.00192*
20,1,.006,.00158,.00192,.00175,.00142,0.0*
1,1,.006,.00175,.00142*
20,1,.006,.00175,.00142,.00167,.00092,0.0*
1,1,.006,.00167,.00092*
20,1,.006,.00167,.00092,.00133,.0005,0.0*
1,1,.006,.00133,.0005*
20,1,.006,.00133,.0005,-.00033,-.00033,0.0*
1,1,.006,-.00033,-.00033*
20,1,.006,-.00033,-.00033,-.00108,-.00092,0.0*
1,1,.006,-.00108,-.00092*
20,1,.006,-.00108,-.00092,-.00158,-.00175,0.0*
1,1,.006,-.00158,-.00175*
20,1,.006,-.00158,-.00175,-.00175,-.0025,0.0*
1,1,.006,-.00175,-.0025*
20,1,.006,-.00175,-.0025,.00175,-.0025,0.0*
1,1,.006,.00175,-.0025*
%
%ADD12MACRO12*%
%AMMACRO25*
1,1,.006,.002899,-.007*
20,1,.006,.002899,-.007,-.002899,-.007,0.0*
1,1,.006,-.002899,-.007*
20,1,.006,-.002899,-.007,-.007,-.002899,0.0*
1,1,.006,-.007,-.002899*
20,1,.006,-.007,-.002899,-.007,.002899,0.0*
1,1,.006,-.007,.002899*
20,1,.006,-.007,.002899,-.002899,.007,0.0*
1,1,.006,-.002899,.007*
20,1,.006,-.002899,.007,.002899,.007,0.0*
1,1,.006,.002899,.007*
20,1,.006,.002899,.007,.007,.002899,0.0*
1,1,.006,.007,.002899*
20,1,.006,.007,.002899,.007,-.002899,0.0*
1,1,.006,.007,-.002899*
20,1,.006,.007,-.002899,.002899,-.007,0.0*
1,1,.006,.002899,-.007*
1,1,.006,-.00257,-.00245*
20,1,.006,-.00257,-.00245,-.00187,-.00303,0.0*
1,1,.006,-.00187,-.00303*
20,1,.006,-.00187,-.00303,-.00105,-.00338,0.0*
1,1,.006,-.00105,-.00338*
20,1,.006,-.00105,-.00338,0.0,-.0035,0.0*
1,1,.006,0.0,-.0035*
20,1,.006,0.0,-.0035,.00105,-.00327,0.0*
1,1,.006,.00105,-.00327*
20,1,.006,.00105,-.00327,.00187,-.0028,0.0*
1,1,.006,.00187,-.0028*
20,1,.006,.00187,-.0028,.00245,-.00198,0.0*
1,1,.006,.00245,-.00198*
20,1,.006,.00245,-.00198,.00257,-.00105,0.0*
1,1,.006,.00257,-.00105*
20,1,.006,.00257,-.00105,.00233,-.00012,0.0*
1,1,.006,.00233,-.00012*
20,1,.006,.00233,-.00012,.00175,.00047,0.0*
1,1,.006,.00175,.00047*
20,1,.006,.00175,.00047,.00093,.00093,0.0*
1,1,.006,.00093,.00093*
20,1,.006,.00093,.00093,.00012,.00105,0.0*
1,1,.006,.00012,.00105*
20,1,.006,.00012,.00105,-.0007,.00093,0.0*
1,1,.006,-.0007,.00093*
20,1,.006,-.0007,.00093,-.00175,.00047,0.0*
1,1,.006,-.00175,.00047*
20,1,.006,-.00175,.00047,-.0014,.0035,0.0*
1,1,.006,-.0014,.0035*
20,1,.006,-.0014,.0035,.00175,.0035,0.0*
1,1,.006,.00175,.0035*
%
%ADD25MACRO25*%
%AMMACRO27*
1,1,.006,.004,0.0*
20,1,.006,.004,0.0,-.004,0.0,0.0*
1,1,.006,-.004,0.0*
1,1,.006,0.0,.004*
20,1,.006,0.0,.004,0.0,-.004,0.0*
1,1,.006,0.0,-.004*
1,1,.006,.002,0.0*
20,1,.006,.002,0.0,.002,.004,0.0*
1,1,.006,.002,.004*
20,1,.006,.002,.004,.0012,.0032,0.0*
1,1,.006,.0012,.0032*
1,1,.006,.0012,0.0*
20,1,.006,.0012,0.0,.0028,0.0,0.0*
1,1,.006,.0028,0.0*
%
%ADD27MACRO27*%
%AMMACRO20*
1,1,.006,-.0154,-.021*
20,1,.006,-.0154,-.021,-.0154,.021,0.0*
1,1,.006,-.0154,.021*
20,1,.006,-.0154,.021,-.0014,.021,0.0*
1,1,.006,-.0014,.021*
20,1,.006,-.0014,.021,.0042,.0189,0.0*
1,1,.006,.0042,.0189*
20,1,.006,.0042,.0189,.0084,.0161,0.0*
1,1,.006,.0084,.0161*
20,1,.006,.0084,.0161,.0119,.0119,0.0*
1,1,.006,.0119,.0119*
20,1,.006,.0119,.0119,.0147,.007,0.0*
1,1,.006,.0147,.007*
20,1,.006,.0147,.007,.0154,0.0,0.0*
1,1,.006,.0154,0.0*
20,1,.006,.0154,0.0,.0147,-.007,0.0*
1,1,.006,.0147,-.007*
20,1,.006,.0147,-.007,.0119,-.0119,0.0*
1,1,.006,.0119,-.0119*
20,1,.006,.0119,-.0119,.0084,-.0161,0.0*
1,1,.006,.0084,-.0161*
20,1,.006,.0084,-.0161,.0042,-.0189,0.0*
1,1,.006,.0042,-.0189*
20,1,.006,.0042,-.0189,-.0014,-.021,0.0*
1,1,.006,-.0014,-.021*
20,1,.006,-.0014,-.021,-.0154,-.021,0.0*
1,1,.006,-.0154,-.021*
%
%ADD20MACRO20*%
%AMMACRO15*
1,1,.006,.05353,.06083*
20,1,.006,.05353,.06083,.03893,.06813,0.0*
1,1,.006,.03893,.06813*
20,1,.006,.03893,.06813,.0219,.073,0.0*
1,1,.006,.0219,.073*
20,1,.006,.0219,.073,.00244,.073,0.0*
1,1,.006,.00244,.073*
20,1,.006,.00244,.073,-.01947,.0657,0.0*
1,1,.006,-.01947,.0657*
20,1,.006,-.01947,.0657,-.0365,.05353,0.0*
1,1,.006,-.0365,.05353*
20,1,.006,-.0365,.05353,-.04867,.03893,0.0*
1,1,.006,-.04867,.03893*
20,1,.006,-.04867,.03893,-.0584,.0146,0.0*
1,1,.006,-.0584,.0146*
20,1,.006,-.0584,.0146,-.06084,-.0073,0.0*
1,1,.006,-.06084,-.0073*
20,1,.006,-.06084,-.0073,-.05597,-.0292,0.0*
1,1,.006,-.05597,-.0292*
20,1,.006,-.05597,-.0292,-.04867,-.0438,0.0*
1,1,.006,-.04867,-.0438*
20,1,.006,-.04867,-.0438,-.03407,-.0584,0.0*
1,1,.006,-.03407,-.0584*
20,1,.006,-.03407,-.0584,-.01703,-.06813,0.0*
1,1,.006,-.01703,-.06813*
20,1,.006,-.01703,-.06813,0.0,-.073,0.0*
1,1,.006,0.0,-.073*
20,1,.006,0.0,-.073,.01703,-.073,0.0*
1,1,.006,.01703,-.073*
20,1,.006,.01703,-.073,.03407,-.06813,0.0*
1,1,.006,.03407,-.06813*
20,1,.006,.03407,-.06813,.04867,-.06084,0.0*
1,1,.006,.04867,-.06084*
20,1,.006,.04867,-.06084,.06084,-.0511,0.0*
1,1,.006,.06084,-.0511*
%
%ADD15MACRO15*%
%AMMACRO23*
1,1,.006,.0184,.0046*
20,1,.006,.0184,.0046,.0276,.0115,0.0*
1,1,.006,.0276,.0115*
20,1,.006,.0276,.0115,.0345,.023,0.0*
1,1,.006,.0345,.023*
20,1,.006,.0345,.023,.0391,.0391,0.0*
1,1,.006,.0391,.0391*
20,1,.006,.0391,.0391,.0345,.0529,0.0*
1,1,.006,.0345,.0529*
20,1,.006,.0345,.0529,.0253,.0621,0.0*
1,1,.006,.0253,.0621*
20,1,.006,.0253,.0621,.0092,.069,0.0*
1,1,.006,.0092,.069*
20,1,.006,.0092,.069,-.0529,.069,0.0*
1,1,.006,-.0529,.069*
20,1,.006,-.0529,.069,-.0529,-.069,0.0*
1,1,.006,-.0529,-.069*
20,1,.006,-.0529,-.069,.023,-.069,0.0*
1,1,.006,.023,-.069*
20,1,.006,.023,-.069,.0391,-.0598,0.0*
1,1,.006,.0391,-.0598*
20,1,.006,.0391,-.0598,.0483,-.046,0.0*
1,1,.006,.0483,-.046*
20,1,.006,.0483,-.046,.0529,-.0299,0.0*
1,1,.006,.0529,-.0299*
20,1,.006,.0529,-.0299,.0483,-.0138,0.0*
1,1,.006,.0483,-.0138*
20,1,.006,.0483,-.0138,.0345,0.0,0.0*
1,1,.006,.0345,0.0*
20,1,.006,.0345,0.0,.0184,.0046,0.0*
1,1,.006,.0184,.0046*
20,1,.006,.0184,.0046,-.0529,.0046,0.0*
1,1,.006,-.0529,.0046*
%
%ADD23MACRO23*%
%AMMACRO24*
1,1,.006,.007085,0.0*
20,1,.006,.007085,0.0,0.0,-.007085,0.0*
1,1,.006,0.0,-.007085*
20,1,.006,0.0,-.007085,-.007085,0.0,0.0*
1,1,.006,-.007085,0.0*
20,1,.006,-.007085,0.0,0.0,.007085,0.0*
1,1,.006,0.0,.007085*
20,1,.006,0.0,.007085,.007085,0.0,0.0*
1,1,.006,.007085,0.0*
1,1,.006,-.00224,-.00059*
20,1,.006,-.00224,-.00059,-.00142,.00024,0.0*
1,1,.006,-.00142,.00024*
20,1,.006,-.00142,.00024,-.00071,.00071,0.0*
1,1,.006,-.00071,.00071*
20,1,.006,-.00071,.00071,.00024,.00094,0.0*
1,1,.006,.00024,.00094*
20,1,.006,.00024,.00094,.00106,.00071,0.0*
1,1,.006,.00106,.00071*
20,1,.006,.00106,.00071,.00165,.00024,0.0*
1,1,.006,.00165,.00024*
20,1,.006,.00165,.00024,.00212,-.00047,0.0*
1,1,.006,.00212,-.00047*
20,1,.006,.00212,-.00047,.00224,-.0013,0.0*
1,1,.006,.00224,-.0013*
20,1,.006,.00224,-.0013,.00212,-.00201,0.0*
1,1,.006,.00212,-.00201*
20,1,.006,.00212,-.00201,.00165,-.00271,0.0*
1,1,.006,.00165,-.00271*
20,1,.006,.00165,-.00271,.00094,-.0033,0.0*
1,1,.006,.00094,-.0033*
20,1,.006,.00094,-.0033,.00012,-.00354,0.0*
1,1,.006,.00012,-.00354*
20,1,.006,.00012,-.00354,-.00083,-.0033,0.0*
1,1,.006,-.00083,-.0033*
20,1,.006,-.00083,-.0033,-.00165,-.0026,0.0*
1,1,.006,-.00165,-.0026*
20,1,.006,-.00165,-.0026,-.00212,-.00153,0.0*
1,1,.006,-.00212,-.00153*
20,1,.006,-.00212,-.00153,-.00224,-.00035,0.0*
1,1,.006,-.00224,-.00035*
20,1,.006,-.00224,-.00035,-.00201,.00118,0.0*
1,1,.006,-.00201,.00118*
20,1,.006,-.00201,.00118,-.00165,.00201,0.0*
1,1,.006,-.00165,.00201*
20,1,.006,-.00165,.00201,-.00106,.00283,0.0*
1,1,.006,-.00106,.00283*
20,1,.006,-.00106,.00283,-.00024,.00342,0.0*
1,1,.006,-.00024,.00342*
20,1,.006,-.00024,.00342,.00059,.00354,0.0*
1,1,.006,.00059,.00354*
20,1,.006,.00059,.00354,.00142,.0033,0.0*
1,1,.006,.00142,.0033*
20,1,.006,.00142,.0033,.00201,.00271,0.0*
1,1,.006,.00201,.00271*
%
%ADD24MACRO24*%
%AMMACRO17*
1,1,.006,-.03458,-.0415*
20,1,.006,-.03458,-.0415,0.0,.0415,0.0*
1,1,.006,0.0,.0415*
20,1,.006,0.0,.0415,.03458,-.0415,0.0*
1,1,.006,.03458,-.0415*
1,1,.006,.02213,-.01245*
20,1,.006,.02213,-.01245,-.02213,-.01245,0.0*
1,1,.006,-.02213,-.01245*
%
%ADD17MACRO17*%
%AMMACRO26*
1,1,.006,-.0238,.0595*
20,1,.006,-.0238,.0595,.0238,.0595,0.0*
1,1,.006,.0238,.0595*
1,1,.006,0.0,.0595*
20,1,.006,0.0,.0595,0.0,-.0595,0.0*
1,1,.006,0.0,-.0595*
1,1,.006,-.0238,-.0595*
20,1,.006,-.0238,-.0595,.0238,-.0595,0.0*
1,1,.006,.0238,-.0595*
%
%ADD26MACRO26*%
%AMMACRO18*
1,1,.006,.0094,0.0*
20,1,.006,.0094,0.0,.04073,0.0,0.0*
1,1,.006,.04073,0.0*
20,1,.006,.04073,0.0,.04073,-.0282,0.0*
1,1,.006,.04073,-.0282*
20,1,.006,.04073,-.0282,.03133,-.0376,0.0*
1,1,.006,.03133,-.0376*
20,1,.006,.03133,-.0376,.02037,-.04387,0.0*
1,1,.006,.02037,-.04387*
20,1,.006,.02037,-.04387,.0047,-.047,0.0*
1,1,.006,.0047,-.047*
20,1,.006,.0047,-.047,-.01097,-.04387,0.0*
1,1,.006,-.01097,-.04387*
20,1,.006,-.01097,-.04387,-.02193,-.0376,0.0*
1,1,.006,-.02193,-.0376*
20,1,.006,-.02193,-.0376,-.03133,-.0282,0.0*
1,1,.006,-.03133,-.0282*
20,1,.006,-.03133,-.0282,-.0376,-.01723,0.0*
1,1,.006,-.0376,-.01723*
20,1,.006,-.0376,-.01723,-.04073,-.0047,0.0*
1,1,.006,-.04073,-.0047*
20,1,.006,-.04073,-.0047,-.04073,.00627,0.0*
1,1,.006,-.04073,.00627*
20,1,.006,-.04073,.00627,-.0376,.01566,0.0*
1,1,.006,-.0376,.01566*
20,1,.006,-.0376,.01566,-.03133,.02663,0.0*
1,1,.006,-.03133,.02663*
20,1,.006,-.03133,.02663,-.02193,.03603,0.0*
1,1,.006,-.02193,.03603*
20,1,.006,-.02193,.03603,-.01253,.0423,0.0*
1,1,.006,-.01253,.0423*
20,1,.006,-.01253,.0423,0.0,.047,0.0*
1,1,.006,0.0,.047*
20,1,.006,0.0,.047,.01097,.047,0.0*
1,1,.006,.01097,.047*
20,1,.006,.01097,.047,.0235,.04387,0.0*
1,1,.006,.0235,.04387*
20,1,.006,.0235,.04387,.0329,.0376,0.0*
1,1,.006,.0329,.0376*
%
%ADD18MACRO18*%
%AMMACRO10*
1,1,.006,.02867,-.043*
20,1,.006,.02867,-.043,-.02867,-.043,0.0*
1,1,.006,-.02867,-.043*
20,1,.006,-.02867,-.043,-.02867,.043,0.0*
1,1,.006,-.02867,.043*
20,1,.006,-.02867,.043,.02867,.043,0.0*
1,1,.006,.02867,.043*
1,1,.006,.00573,.00143*
20,1,.006,.00573,.00143,-.02867,.00143,0.0*
1,1,.006,-.02867,.00143*
%
%ADD10MACRO10*%
%AMMACRO28*
1,1,.006,-.02755,-.0435*
20,1,.006,-.02755,-.0435,-.02755,.0435,0.0*
1,1,.006,-.02755,.0435*
20,1,.006,-.02755,.0435,.02755,.0435,0.0*
1,1,.006,.02755,.0435*
1,1,.006,.00725,.00145*
20,1,.006,.00725,.00145,-.02755,.00145,0.0*
1,1,.006,-.02755,.00145*
%
%ADD28MACRO28*%
%AMMACRO19*
1,1,.006,-.03395,-.0485*
20,1,.006,-.03395,-.0485,-.03395,.0485,0.0*
1,1,.006,-.03395,.0485*
1,1,.006,.03395,.0485*
20,1,.006,.03395,.0485,.03395,-.0485,0.0*
1,1,.006,.03395,-.0485*
1,1,.006,.03395,0.0*
20,1,.006,.03395,0.0,-.03395,0.0,0.0*
1,1,.006,-.03395,0.0*
%
%ADD19MACRO19*%
%AMMACRO22*
1,1,.006,.005,0.0*
20,1,.006,.005,0.0,.0025,.00433,0.0*
1,1,.006,.0025,.00433*
20,1,.006,.0025,.00433,-.0025,.00433,0.0*
1,1,.006,-.0025,.00433*
20,1,.006,-.0025,.00433,-.005,0.0,0.0*
1,1,.006,-.005,0.0*
20,1,.006,-.005,0.0,-.0025,-.00433,0.0*
1,1,.006,-.0025,-.00433*
20,1,.006,-.0025,-.00433,.0025,-.00433,0.0*
1,1,.006,.0025,-.00433*
20,1,.006,.0025,-.00433,.005,0.0,0.0*
1,1,.006,.005,0.0*
1,1,.006,-.00183,-.0015*
20,1,.006,-.00183,-.0015,-.00133,-.00208,0.0*
1,1,.006,-.00133,-.00208*
20,1,.006,-.00133,-.00208,-.00067,-.00242,0.0*
1,1,.006,-.00067,-.00242*
20,1,.006,-.00067,-.00242,.00008,-.0025,0.0*
1,1,.006,.00008,-.0025*
20,1,.006,.00008,-.0025,.00075,-.00242,0.0*
1,1,.006,.00075,-.00242*
20,1,.006,.00075,-.00242,.00142,-.002,0.0*
1,1,.006,.00142,-.002*
20,1,.006,.00142,-.002,.00183,-.0015,0.0*
1,1,.006,.00183,-.0015*
20,1,.006,.00183,-.0015,.00192,-.001,0.0*
1,1,.006,.00192,-.001*
20,1,.006,.00192,-.001,.00175,-.00042,0.0*
1,1,.006,.00175,-.00042*
20,1,.006,.00175,-.00042,.00117,0.0,0.0*
1,1,.006,.00117,0.0*
20,1,.006,.00117,0.0,.00058,.00017,0.0*
1,1,.006,.00058,.00017*
20,1,.006,.00058,.00017,-.00017,.00017,0.0*
1,1,.006,-.00017,.00017*
1,1,.006,.00058,.00017*
20,1,.006,.00058,.00017,.00108,.00042,0.0*
1,1,.006,.00108,.00042*
20,1,.006,.00108,.00042,.0015,.00083,0.0*
1,1,.006,.0015,.00083*
20,1,.006,.0015,.00083,.00167,.00133,0.0*
1,1,.006,.00167,.00133*
20,1,.006,.00167,.00133,.0015,.00183,0.0*
1,1,.006,.0015,.00183*
20,1,.006,.0015,.00183,.00108,.00225,0.0*
1,1,.006,.00108,.00225*
20,1,.006,.00108,.00225,.00033,.0025,0.0*
1,1,.006,.00033,.0025*
20,1,.006,.00033,.0025,-.00042,.00242,0.0*
1,1,.006,-.00042,.00242*
20,1,.006,-.00042,.00242,-.00117,.00208,0.0*
1,1,.006,-.00117,.00208*
%
%ADD22MACRO22*%
%AMMACRO14*
1,1,.006,0.0,.006*
20,1,.006,0.0,.006,-.005196,.003,0.0*
1,1,.006,-.005196,.003*
20,1,.006,-.005196,.003,-.005196,-.003,0.0*
1,1,.006,-.005196,-.003*
20,1,.006,-.005196,-.003,0.0,-.006,0.0*
1,1,.006,0.0,-.006*
20,1,.006,0.0,-.006,.005196,-.003,0.0*
1,1,.006,.005196,-.003*
20,1,.006,.005196,-.003,.005196,.003,0.0*
1,1,.006,.005196,.003*
20,1,.006,.005196,.003,0.0,.006,0.0*
1,1,.006,0.0,.006*
1,1,.006,.0012,-.003*
20,1,.006,.0012,-.003,.0012,.003,0.0*
1,1,.006,.0012,.003*
20,1,.006,.0012,.003,-.0025,-.0013,0.0*
1,1,.006,-.0025,-.0013*
20,1,.006,-.0025,-.0013,.0025,-.0013,0.0*
1,1,.006,.0025,-.0013*
%
%ADD14MACRO14*%
%AMMACRO16*
1,1,.006,.031,0.0*
20,1,.006,.031,0.0,.030529,-.005383,0.0*
1,1,.006,.030529,-.005383*
20,1,.006,.030529,-.005383,.02913,-.010603,0.0*
1,1,.006,.02913,-.010603*
20,1,.006,.02913,-.010603,.026847,-.0155,0.0*
1,1,.006,.026847,-.0155*
20,1,.006,.026847,-.0155,.023747,-.019926,0.0*
1,1,.006,.023747,-.019926*
20,1,.006,.023747,-.019926,.019926,-.023747,0.0*
1,1,.006,.019926,-.023747*
20,1,.006,.019926,-.023747,.0155,-.026847,0.0*
1,1,.006,.0155,-.026847*
20,1,.006,.0155,-.026847,.010603,-.02913,0.0*
1,1,.006,.010603,-.02913*
20,1,.006,.010603,-.02913,.005383,-.030529,0.0*
1,1,.006,.005383,-.030529*
20,1,.006,.005383,-.030529,0.0,-.031,0.0*
1,1,.006,0.0,-.031*
20,1,.006,0.0,-.031,-.005383,-.030529,0.0*
1,1,.006,-.005383,-.030529*
20,1,.006,-.005383,-.030529,-.010603,-.02913,0.0*
1,1,.006,-.010603,-.02913*
20,1,.006,-.010603,-.02913,-.0155,-.026847,0.0*
1,1,.006,-.0155,-.026847*
20,1,.006,-.0155,-.026847,-.019926,-.023747,0.0*
1,1,.006,-.019926,-.023747*
20,1,.006,-.019926,-.023747,-.023747,-.019926,0.0*
1,1,.006,-.023747,-.019926*
20,1,.006,-.023747,-.019926,-.026847,-.0155,0.0*
1,1,.006,-.026847,-.0155*
20,1,.006,-.026847,-.0155,-.02913,-.010603,0.0*
1,1,.006,-.02913,-.010603*
20,1,.006,-.02913,-.010603,-.030529,-.005383,0.0*
1,1,.006,-.030529,-.005383*
20,1,.006,-.030529,-.005383,-.031,0.0,0.0*
1,1,.006,-.031,0.0*
20,1,.006,-.031,0.0,-.030529,.005383,0.0*
1,1,.006,-.030529,.005383*
20,1,.006,-.030529,.005383,-.02913,.010603,0.0*
1,1,.006,-.02913,.010603*
20,1,.006,-.02913,.010603,-.026847,.0155,0.0*
1,1,.006,-.026847,.0155*
20,1,.006,-.026847,.0155,-.023747,.019926,0.0*
1,1,.006,-.023747,.019926*
20,1,.006,-.023747,.019926,-.019926,.023747,0.0*
1,1,.006,-.019926,.023747*
20,1,.006,-.019926,.023747,-.0155,.026847,0.0*
1,1,.006,-.0155,.026847*
20,1,.006,-.0155,.026847,-.010603,.02913,0.0*
1,1,.006,-.010603,.02913*
20,1,.006,-.010603,.02913,-.005383,.030529,0.0*
1,1,.006,-.005383,.030529*
20,1,.006,-.005383,.030529,0.0,.031,0.0*
1,1,.006,0.0,.031*
20,1,.006,0.0,.031,.005383,.030529,0.0*
1,1,.006,.005383,.030529*
20,1,.006,.005383,.030529,.010603,.02913,0.0*
1,1,.006,.010603,.02913*
20,1,.006,.010603,.02913,.0155,.026847,0.0*
1,1,.006,.0155,.026847*
20,1,.006,.0155,.026847,.019926,.023747,0.0*
1,1,.006,.019926,.023747*
20,1,.006,.019926,.023747,.023747,.019926,0.0*
1,1,.006,.023747,.019926*
20,1,.006,.023747,.019926,.026847,.0155,0.0*
1,1,.006,.026847,.0155*
20,1,.006,.026847,.0155,.02913,.010603,0.0*
1,1,.006,.02913,.010603*
20,1,.006,.02913,.010603,.030529,.005383,0.0*
1,1,.006,.030529,.005383*
20,1,.006,.030529,.005383,.031,0.0,0.0*
1,1,.006,.031,0.0*
1,1,.006,-.0155,-.0155*
20,1,.006,-.0155,-.0155,-.0155,.0155,0.0*
1,1,.006,-.0155,.0155*
20,1,.006,-.0155,.0155,-.0217,.0093,0.0*
1,1,.006,-.0217,.0093*
1,1,.006,-.0217,-.0155*
20,1,.006,-.0217,-.0155,-.0093,-.0155,0.0*
1,1,.006,-.0093,-.0155*
1,1,.006,.01551,-.0155*
20,1,.006,.01551,-.0155,.01551,.0155,0.0*
1,1,.006,.01551,.0155*
20,1,.006,.01551,.0155,.00931,.0093,0.0*
1,1,.006,.00931,.0093*
1,1,.006,.00931,-.0155*
20,1,.006,.00931,-.0155,.02171,-.0155,0.0*
1,1,.006,.02171,-.0155*
%
%ADD16MACRO16*%
%AMMACRO13*
1,1,.006,-.0075,.0025*
20,1,.006,-.0075,.0025,-.007386,.003802,0.0*
1,1,.006,-.007386,.003802*
20,1,.006,-.007386,.003802,-.007048,.005065,0.0*
1,1,.006,-.007048,.005065*
20,1,.006,-.007048,.005065,-.006495,.00625,0.0*
1,1,.006,-.006495,.00625*
20,1,.006,-.006495,.00625,-.005745,.007321,0.0*
1,1,.006,-.005745,.007321*
20,1,.006,-.005745,.007321,-.004821,.008245,0.0*
1,1,.006,-.004821,.008245*
20,1,.006,-.004821,.008245,-.00375,.008995,0.0*
1,1,.006,-.00375,.008995*
20,1,.006,-.00375,.008995,-.002565,.009548,0.0*
1,1,.006,-.002565,.009548*
20,1,.006,-.002565,.009548,-.001302,.009886,0.0*
1,1,.006,-.001302,.009886*
20,1,.006,-.001302,.009886,0.0,.01,0.0*
1,1,.006,0.0,.01*
20,1,.006,0.0,.01,.001302,.009886,0.0*
1,1,.006,.001302,.009886*
20,1,.006,.001302,.009886,.002565,.009548,0.0*
1,1,.006,.002565,.009548*
20,1,.006,.002565,.009548,.00375,.008995,0.0*
1,1,.006,.00375,.008995*
20,1,.006,.00375,.008995,.004821,.008245,0.0*
1,1,.006,.004821,.008245*
20,1,.006,.004821,.008245,.005745,.007321,0.0*
1,1,.006,.005745,.007321*
20,1,.006,.005745,.007321,.006495,.00625,0.0*
1,1,.006,.006495,.00625*
20,1,.006,.006495,.00625,.007048,.005065,0.0*
1,1,.006,.007048,.005065*
20,1,.006,.007048,.005065,.007386,.003802,0.0*
1,1,.006,.007386,.003802*
20,1,.006,.007386,.003802,.0075,.0025,0.0*
1,1,.006,.0075,.0025*
20,1,.006,.0075,.0025,.0075,-.0025,0.0*
1,1,.006,.0075,-.0025*
20,1,.006,.0075,-.0025,.007386,-.003802,0.0*
1,1,.006,.007386,-.003802*
20,1,.006,.007386,-.003802,.007048,-.005065,0.0*
1,1,.006,.007048,-.005065*
20,1,.006,.007048,-.005065,.006495,-.00625,0.0*
1,1,.006,.006495,-.00625*
20,1,.006,.006495,-.00625,.005745,-.007321,0.0*
1,1,.006,.005745,-.007321*
20,1,.006,.005745,-.007321,.004821,-.008245,0.0*
1,1,.006,.004821,-.008245*
20,1,.006,.004821,-.008245,.00375,-.008995,0.0*
1,1,.006,.00375,-.008995*
20,1,.006,.00375,-.008995,.002565,-.009548,0.0*
1,1,.006,.002565,-.009548*
20,1,.006,.002565,-.009548,.001302,-.009886,0.0*
1,1,.006,.001302,-.009886*
20,1,.006,.001302,-.009886,0.0,-.01,0.0*
1,1,.006,0.0,-.01*
20,1,.006,0.0,-.01,-.001302,-.009886,0.0*
1,1,.006,-.001302,-.009886*
20,1,.006,-.001302,-.009886,-.002565,-.009548,0.0*
1,1,.006,-.002565,-.009548*
20,1,.006,-.002565,-.009548,-.00375,-.008995,0.0*
1,1,.006,-.00375,-.008995*
20,1,.006,-.00375,-.008995,-.004821,-.008245,0.0*
1,1,.006,-.004821,-.008245*
20,1,.006,-.004821,-.008245,-.005745,-.007321,0.0*
1,1,.006,-.005745,-.007321*
20,1,.006,-.005745,-.007321,-.006495,-.00625,0.0*
1,1,.006,-.006495,-.00625*
20,1,.006,-.006495,-.00625,-.007048,-.005065,0.0*
1,1,.006,-.007048,-.005065*
20,1,.006,-.007048,-.005065,-.007386,-.003802,0.0*
1,1,.006,-.007386,-.003802*
20,1,.006,-.007386,-.003802,-.0075,-.0025,0.0*
1,1,.006,-.0075,-.0025*
20,1,.006,-.0075,-.0025,-.0075,.0025,0.0*
1,1,.006,-.0075,.0025*
1,1,.006,-.00213,-.00288*
20,1,.006,-.00213,-.00288,-.00125,-.0035,0.0*
1,1,.006,-.00125,-.0035*
20,1,.006,-.00125,-.0035,-.00025,-.00375,0.0*
1,1,.006,-.00025,-.00375*
20,1,.006,-.00025,-.00375,.00075,-.0035,0.0*
1,1,.006,.00075,-.0035*
20,1,.006,.00075,-.0035,.00162,-.00275,0.0*
1,1,.006,.00162,-.00275*
20,1,.006,.00162,-.00275,.00225,-.00162,0.0*
1,1,.006,.00225,-.00162*
20,1,.006,.00225,-.00162,.0025,-.0005,0.0*
1,1,.006,.0025,-.0005*
20,1,.006,.0025,-.0005,.0025,.00087,0.0*
1,1,.006,.0025,.00087*
20,1,.006,.0025,.00087,.00225,.002,0.0*
1,1,.006,.00225,.002*
20,1,.006,.00225,.002,.00162,.003,0.0*
1,1,.006,.00162,.003*
20,1,.006,.00162,.003,.00087,.0035,0.0*
1,1,.006,.00087,.0035*
20,1,.006,.00087,.0035,0.0,.00375,0.0*
1,1,.006,0.0,.00375*
20,1,.006,0.0,.00375,-.001,.0035,0.0*
1,1,.006,-.001,.0035*
20,1,.006,-.001,.0035,-.00175,.003,0.0*
1,1,.006,-.00175,.003*
20,1,.006,-.00175,.003,-.00225,.00225,0.0*
1,1,.006,-.00225,.00225*
20,1,.006,-.00225,.00225,-.0025,.00125,0.0*
1,1,.006,-.0025,.00125*
20,1,.006,-.0025,.00125,-.00225,.00038,0.0*
1,1,.006,-.00225,.00038*
20,1,.006,-.00225,.00038,-.00162,-.0005,0.0*
1,1,.006,-.00162,-.0005*
20,1,.006,-.00162,-.0005,-.00087,-.001,0.0*
1,1,.006,-.00087,-.001*
20,1,.006,-.00087,-.001,0.0,-.00113,0.0*
1,1,.006,0.0,-.00113*
20,1,.006,0.0,-.00113,.001,-.00088,0.0*
1,1,.006,.001,-.00088*
20,1,.006,.001,-.00088,.00175,-.00025,0.0*
1,1,.006,.00175,-.00025*
20,1,.006,.00175,-.00025,.0025,.00087,0.0*
1,1,.006,.0025,.00087*
%
%ADD13MACRO13*%
%AMMACRO11*
1,1,.006,-.002,.006*
20,1,.006,-.002,.006,.002,.006,0.0*
1,1,.006,.002,.006*
20,1,.006,.002,.006,.003042,.005909,0.0*
1,1,.006,.003042,.005909*
20,1,.006,.003042,.005909,.004052,.005638,0.0*
1,1,.006,.004052,.005638*
20,1,.006,.004052,.005638,.005,.005196,0.0*
1,1,.006,.005,.005196*
20,1,.006,.005,.005196,.005857,.004596,0.0*
1,1,.006,.005857,.004596*
20,1,.006,.005857,.004596,.006596,.003857,0.0*
1,1,.006,.006596,.003857*
20,1,.006,.006596,.003857,.007196,.003,0.0*
1,1,.006,.007196,.003*
20,1,.006,.007196,.003,.007638,.002052,0.0*
1,1,.006,.007638,.002052*
20,1,.006,.007638,.002052,.007909,.001042,0.0*
1,1,.006,.007909,.001042*
20,1,.006,.007909,.001042,.008,0.0,0.0*
1,1,.006,.008,0.0*
20,1,.006,.008,0.0,.007909,-.001042,0.0*
1,1,.006,.007909,-.001042*
20,1,.006,.007909,-.001042,.007638,-.002052,0.0*
1,1,.006,.007638,-.002052*
20,1,.006,.007638,-.002052,.007196,-.003,0.0*
1,1,.006,.007196,-.003*
20,1,.006,.007196,-.003,.006596,-.003857,0.0*
1,1,.006,.006596,-.003857*
20,1,.006,.006596,-.003857,.005857,-.004596,0.0*
1,1,.006,.005857,-.004596*
20,1,.006,.005857,-.004596,.005,-.005196,0.0*
1,1,.006,.005,-.005196*
20,1,.006,.005,-.005196,.004052,-.005638,0.0*
1,1,.006,.004052,-.005638*
20,1,.006,.004052,-.005638,.003042,-.005909,0.0*
1,1,.006,.003042,-.005909*
20,1,.006,.003042,-.005909,.002,-.006,0.0*
1,1,.006,.002,-.006*
20,1,.006,.002,-.006,-.002,-.006,0.0*
1,1,.006,-.002,-.006*
20,1,.006,-.002,-.006,-.003042,-.005909,0.0*
1,1,.006,-.003042,-.005909*
20,1,.006,-.003042,-.005909,-.004052,-.005638,0.0*
1,1,.006,-.004052,-.005638*
20,1,.006,-.004052,-.005638,-.005,-.005196,0.0*
1,1,.006,-.005,-.005196*
20,1,.006,-.005,-.005196,-.005857,-.004596,0.0*
1,1,.006,-.005857,-.004596*
20,1,.006,-.005857,-.004596,-.006596,-.003857,0.0*
1,1,.006,-.006596,-.003857*
20,1,.006,-.006596,-.003857,-.007196,-.003,0.0*
1,1,.006,-.007196,-.003*
20,1,.006,-.007196,-.003,-.007638,-.002052,0.0*
1,1,.006,-.007638,-.002052*
20,1,.006,-.007638,-.002052,-.007909,-.001042,0.0*
1,1,.006,-.007909,-.001042*
20,1,.006,-.007909,-.001042,-.008,0.0,0.0*
1,1,.006,-.008,0.0*
20,1,.006,-.008,0.0,-.007909,.001042,0.0*
1,1,.006,-.007909,.001042*
20,1,.006,-.007909,.001042,-.007638,.002052,0.0*
1,1,.006,-.007638,.002052*
20,1,.006,-.007638,.002052,-.007196,.003,0.0*
1,1,.006,-.007196,.003*
20,1,.006,-.007196,.003,-.006596,.003857,0.0*
1,1,.006,-.006596,.003857*
20,1,.006,-.006596,.003857,-.005857,.004596,0.0*
1,1,.006,-.005857,.004596*
20,1,.006,-.005857,.004596,-.005,.005196,0.0*
1,1,.006,-.005,.005196*
20,1,.006,-.005,.005196,-.004052,.005638,0.0*
1,1,.006,-.004052,.005638*
20,1,.006,-.004052,.005638,-.003042,.005909,0.0*
1,1,.006,-.003042,.005909*
20,1,.006,-.003042,.005909,-.002,.006,0.0*
1,1,.006,-.002,.006*
1,1,.006,0.0,-.003*
20,1,.006,0.0,-.003,.0007,-.0029,0.0*
1,1,.006,.0007,-.0029*
20,1,.006,.0007,-.0029,.0015,-.0026,0.0*
1,1,.006,.0015,-.0026*
20,1,.006,.0015,-.0026,.002,-.0021,0.0*
1,1,.006,.002,-.0021*
20,1,.006,.002,-.0021,.0022,-.0014,0.0*
1,1,.006,.0022,-.0014*
20,1,.006,.0022,-.0014,.002,-.0007,0.0*
1,1,.006,.002,-.0007*
20,1,.006,.002,-.0007,.0014,-.0001,0.0*
1,1,.006,.0014,-.0001*
20,1,.006,.0014,-.0001,.0005,.0002,0.0*
1,1,.006,.0005,.0002*
20,1,.006,.0005,.0002,-.0005,.0002,0.0*
1,1,.006,-.0005,.0002*
20,1,.006,-.0005,.0002,-.0011,.0004,0.0*
1,1,.006,-.0011,.0004*
20,1,.006,-.0011,.0004,-.0016,.0009,0.0*
1,1,.006,-.0016,.0009*
20,1,.006,-.0016,.0009,-.0018,.0016,0.0*
1,1,.006,-.0018,.0016*
20,1,.006,-.0018,.0016,-.0015,.0023,0.0*
1,1,.006,-.0015,.0023*
20,1,.006,-.0015,.0023,-.0008,.0028,0.0*
1,1,.006,-.0008,.0028*
20,1,.006,-.0008,.0028,0.0,.003,0.0*
1,1,.006,0.0,.003*
20,1,.006,0.0,.003,.0008,.0028,0.0*
1,1,.006,.0008,.0028*
20,1,.006,.0008,.0028,.0015,.0023,0.0*
1,1,.006,.0015,.0023*
20,1,.006,.0015,.0023,.0018,.0016,0.0*
1,1,.006,.0018,.0016*
20,1,.006,.0018,.0016,.0016,.0009,0.0*
1,1,.006,.0016,.0009*
20,1,.006,.0016,.0009,.0011,.0004,0.0*
1,1,.006,.0011,.0004*
20,1,.006,.0011,.0004,.0005,.0002,0.0*
1,1,.006,.0005,.0002*
20,1,.006,.0005,.0002,-.0005,.0002,0.0*
1,1,.006,-.0005,.0002*
20,1,.006,-.0005,.0002,-.0014,-.0001,0.0*
1,1,.006,-.0014,-.0001*
20,1,.006,-.0014,-.0001,-.002,-.0007,0.0*
1,1,.006,-.002,-.0007*
20,1,.006,-.002,-.0007,-.0022,-.0014,0.0*
1,1,.006,-.0022,-.0014*
20,1,.006,-.0022,-.0014,-.002,-.0021,0.0*
1,1,.006,-.002,-.0021*
20,1,.006,-.002,-.0021,-.0015,-.0026,0.0*
1,1,.006,-.0015,-.0026*
20,1,.006,-.0015,-.0026,-.0007,-.0029,0.0*
1,1,.006,-.0007,-.0029*
20,1,.006,-.0007,-.0029,0.0,-.003,0.0*
1,1,.006,0.0,-.003*
%
%ADD11MACRO11*%
%AMMACRO21*
1,1,.006,.014565,.010925*
20,1,.006,.014565,.010925,.014565,-.010925,0.0*
1,1,.006,.014565,-.010925*
20,1,.006,.014565,-.010925,-.014565,-.010925,0.0*
1,1,.006,-.014565,-.010925*
20,1,.006,-.014565,-.010925,-.014565,.010925,0.0*
1,1,.006,-.014565,.010925*
20,1,.006,-.014565,.010925,.014565,.010925,0.0*
1,1,.006,.014565,.010925*
1,1,.006,-.00546,-.00546*
20,1,.006,-.00546,-.00546,-.00546,.00546,0.0*
1,1,.006,-.00546,.00546*
20,1,.006,-.00546,.00546,-.00764,.00328,0.0*
1,1,.006,-.00764,.00328*
1,1,.006,-.00764,-.00546*
20,1,.006,-.00764,-.00546,-.00328,-.00546,0.0*
1,1,.006,-.00328,-.00546*
1,1,.006,.00547,.00546*
20,1,.006,.00547,.00546,.00401,.0051,0.0*
1,1,.006,.00401,.0051*
20,1,.006,.00401,.0051,.00292,.00419,0.0*
1,1,.006,.00292,.00419*
20,1,.006,.00292,.00419,.00219,.00309,0.0*
1,1,.006,.00219,.00309*
20,1,.006,.00219,.00309,.00165,.00164,0.0*
1,1,.006,.00165,.00164*
20,1,.006,.00165,.00164,.00147,0.0,0.0*
1,1,.006,.00147,0.0*
20,1,.006,.00147,0.0,.00165,-.00164,0.0*
1,1,.006,.00165,-.00164*
20,1,.006,.00165,-.00164,.00219,-.00309,0.0*
1,1,.006,.00219,-.00309*
20,1,.006,.00219,-.00309,.00292,-.00419,0.0*
1,1,.006,.00292,-.00419*
20,1,.006,.00292,-.00419,.00401,-.0051,0.0*
1,1,.006,.00401,-.0051*
20,1,.006,.00401,-.0051,.00547,-.00546,0.0*
1,1,.006,.00547,-.00546*
20,1,.006,.00547,-.00546,.00693,-.0051,0.0*
1,1,.006,.00693,-.0051*
20,1,.006,.00693,-.0051,.00802,-.00419,0.0*
1,1,.006,.00802,-.00419*
20,1,.006,.00802,-.00419,.00875,-.00309,0.0*
1,1,.006,.00875,-.00309*
20,1,.006,.00875,-.00309,.00929,-.00164,0.0*
1,1,.006,.00929,-.00164*
20,1,.006,.00929,-.00164,.00947,0.0,0.0*
1,1,.006,.00947,0.0*
20,1,.006,.00947,0.0,.00929,.00164,0.0*
1,1,.006,.00929,.00164*
20,1,.006,.00929,.00164,.00875,.00309,0.0*
1,1,.006,.00875,.00309*
20,1,.006,.00875,.00309,.00802,.00419,0.0*
1,1,.006,.00802,.00419*
20,1,.006,.00802,.00419,.00693,.0051,0.0*
1,1,.006,.00693,.0051*
20,1,.006,.00693,.0051,.00547,.00546,0.0*
1,1,.006,.00547,.00546*
%
%ADD21MACRO21*%
%ADD30C,.02*%
%ADD31C,.006*%
G75*
%LPD*%
G75*
G54D10*
X15812Y-86244D03*
X27058Y25484D03*
X81539Y542850D03*
X411652Y539991D03*
X812711Y-86834D03*
X798456Y26432D03*
X1019575Y153903D03*
G54D11*
X15364Y5500D03*
X10364D03*
X5500Y10384D03*
Y15384D03*
Y20384D03*
Y25384D03*
Y30384D03*
Y35384D03*
Y40384D03*
Y45384D03*
Y50384D03*
Y55384D03*
Y60384D03*
Y65384D03*
Y70384D03*
Y75384D03*
Y80384D03*
Y85384D03*
Y90384D03*
Y95384D03*
Y100384D03*
Y105384D03*
Y110384D03*
Y115384D03*
Y120384D03*
Y125384D03*
Y130384D03*
Y135384D03*
Y140384D03*
Y145384D03*
Y150384D03*
Y155384D03*
Y160384D03*
Y165384D03*
Y170384D03*
Y175384D03*
Y180384D03*
Y185384D03*
Y190384D03*
Y195384D03*
Y200384D03*
Y205384D03*
Y210384D03*
Y215384D03*
Y220384D03*
Y225384D03*
Y230384D03*
Y235384D03*
Y240384D03*
Y245384D03*
Y250384D03*
Y255384D03*
Y260384D03*
Y265384D03*
Y270384D03*
Y275384D03*
Y280384D03*
Y285384D03*
Y290384D03*
Y295384D03*
Y300384D03*
Y305384D03*
Y310384D03*
Y315384D03*
Y320384D03*
Y325384D03*
Y330384D03*
Y335384D03*
Y340384D03*
Y345384D03*
Y350384D03*
Y355384D03*
Y360384D03*
Y365384D03*
Y370384D03*
Y375384D03*
Y380384D03*
Y385384D03*
Y390384D03*
Y395384D03*
Y400384D03*
Y405384D03*
Y410384D03*
Y415384D03*
Y420384D03*
Y425384D03*
Y430384D03*
Y435384D03*
Y440384D03*
Y445384D03*
Y450384D03*
Y455384D03*
Y460384D03*
Y465384D03*
Y470384D03*
Y475384D03*
Y480384D03*
Y485384D03*
Y530384D03*
Y525384D03*
Y520384D03*
Y515384D03*
Y510384D03*
Y505384D03*
Y490384D03*
Y495384D03*
Y500384D03*
Y535384D03*
Y540384D03*
Y545384D03*
Y550384D03*
Y555384D03*
Y560384D03*
X10266Y565366D03*
X15266D03*
X75364Y5500D03*
X70364D03*
X65364D03*
X60364D03*
X55364D03*
X50364D03*
X45364D03*
X40364D03*
X35364D03*
X30364D03*
X25364D03*
X20364D03*
X75119Y111166D03*
X20266Y565366D03*
X25266D03*
X30266D03*
X35266D03*
X40266D03*
X45266D03*
X50266D03*
X55266D03*
X60266D03*
X65266D03*
X70266D03*
X75266D03*
X95364Y5500D03*
X90364D03*
X85364D03*
X80364D03*
X105619Y111166D03*
X81119D03*
X87619D03*
X93619D03*
X99619D03*
X128580Y170810D03*
X122984Y170984D03*
X123200Y175800D03*
X125741Y166309D03*
X128459Y175658D03*
X140000Y204950D03*
X94080Y448470D03*
X80266Y565366D03*
X85266D03*
X90266D03*
X95266D03*
X100266D03*
X105266D03*
X110266D03*
X115266D03*
X120266D03*
X125266D03*
X130266D03*
X135266D03*
X200364Y5500D03*
X195364D03*
X190364D03*
X185364D03*
X180364D03*
X175364D03*
X170364D03*
X192830Y170500D03*
X197630D03*
X192830Y165700D03*
X197630D03*
X192830Y160900D03*
X197630D03*
X170900Y160500D03*
X151500D03*
X156300D03*
X161100D03*
X165900D03*
X198557Y153196D03*
X191900Y196100D03*
X196900D03*
X201700D03*
X196900Y200900D03*
X191900D03*
X196900Y205700D03*
X191900D03*
X196900Y210500D03*
X191900D03*
X201700Y205700D03*
Y200900D03*
X151500Y205000D03*
X156300D03*
X161100D03*
X165900D03*
X170900D03*
X178450Y203150D03*
X144800Y204950D03*
X177850Y324800D03*
X174995Y353588D03*
Y358388D03*
X165195D03*
X169995D03*
Y353588D03*
X197718Y350937D03*
Y355859D03*
X157650Y418100D03*
X160400Y422900D03*
X160550Y414100D03*
X177468Y417900D03*
X142865Y424021D03*
X143608Y415900D03*
X158067Y378857D03*
X160400Y427700D03*
Y432500D03*
X176311Y445493D03*
X176423Y440472D03*
X177421Y432909D03*
X177532Y426134D03*
X145392Y445207D03*
X145456Y440338D03*
X142991Y430900D03*
X200266Y565366D03*
X195266D03*
X190266D03*
X185266D03*
X180266D03*
X175266D03*
X140266D03*
X145266D03*
X150266D03*
X155266D03*
X160266D03*
X165266D03*
X170266D03*
X260364Y5500D03*
X255364D03*
X250364D03*
X245364D03*
X240364D03*
X235364D03*
X230364D03*
X225364D03*
X220364D03*
X215364D03*
X210364D03*
X205364D03*
X222700Y149300D03*
X227500D03*
X222700Y144500D03*
X227500D03*
X222700Y139700D03*
X227500D03*
X222700Y158900D03*
X227500D03*
X222700Y154100D03*
X227500D03*
X202430Y170500D03*
Y165700D03*
Y160900D03*
X253600Y139500D03*
Y134700D03*
X251800Y153600D03*
Y144000D03*
Y148800D03*
X258400Y134700D03*
Y139500D03*
X263200Y134700D03*
Y139500D03*
X222800Y204600D03*
X227600D03*
X222800Y219000D03*
X227600D03*
X222800Y214200D03*
X227600D03*
X222800Y209400D03*
X227600D03*
X222490Y235373D03*
X227290D03*
X222246Y229952D03*
X227046D03*
X222800Y223800D03*
X227600D03*
X253600Y230500D03*
Y225700D03*
Y220900D03*
X258400Y230500D03*
Y225700D03*
Y220900D03*
X263200Y230500D03*
Y225700D03*
Y220900D03*
X222460Y240264D03*
X227260D03*
X249204Y244103D03*
X254300Y357732D03*
X222818Y364806D03*
X222909Y371864D03*
X223000Y378246D03*
X246700Y418600D03*
X209052Y470198D03*
X213700Y448450D03*
X208900D03*
X203000Y451300D03*
X204252Y470198D03*
X204364Y478917D03*
X209164D03*
X212589Y494694D03*
X220589D03*
X216589Y489694D03*
X208589D03*
X224589D03*
X205266Y565366D03*
X210266D03*
X215266D03*
X220266D03*
X225266D03*
X230266D03*
X235266D03*
X240266D03*
X245266D03*
X250266D03*
X255266D03*
X260266D03*
X325364Y5500D03*
X320364D03*
X315364D03*
X310364D03*
X305364D03*
X300364D03*
X295364D03*
X290364D03*
X285364D03*
X280364D03*
X275364D03*
X270364D03*
X265364D03*
X295960Y148987D03*
Y154387D03*
X308907Y171800D03*
Y166400D03*
Y161000D03*
X287000Y117600D03*
Y125000D03*
X285500Y130400D03*
X290300D03*
X287300Y173000D03*
X292100D03*
X295650Y169554D03*
X295100Y130400D03*
X272800Y168000D03*
Y172800D03*
Y134700D03*
X268000Y165962D03*
X268064Y171792D03*
X268000Y158700D03*
Y153900D03*
Y134700D03*
Y139500D03*
Y144300D03*
Y149100D03*
X296200Y195900D03*
Y190500D03*
X308907Y215200D03*
Y220600D03*
Y226000D03*
Y231400D03*
Y236800D03*
Y209800D03*
Y188200D03*
Y199000D03*
Y204400D03*
Y177200D03*
Y193600D03*
Y182800D03*
X296400Y237950D03*
Y232550D03*
X295801Y210294D03*
X292600Y214500D03*
X287800D03*
X272800Y177600D03*
X268064Y184062D03*
X268000Y235300D03*
Y230500D03*
Y225700D03*
Y220900D03*
Y216000D03*
Y211200D03*
X268118Y191305D03*
X268000Y206400D03*
Y196800D03*
Y201600D03*
Y178062D03*
X308907Y242200D03*
X295879Y255540D03*
X291079D03*
X286279D03*
X266404Y249707D03*
X268000Y244900D03*
Y240100D03*
X276070Y395357D03*
X265266Y565366D03*
X270266D03*
X275266D03*
X280266D03*
X285266D03*
X290266D03*
X295266D03*
X300266D03*
X305266D03*
X310266D03*
X315266D03*
X320266D03*
X325266D03*
X330364Y5500D03*
X346700Y296333D03*
Y291533D03*
X350586Y495815D03*
X355523Y495025D03*
X360461Y494236D03*
X365398Y493446D03*
X370335Y492656D03*
X375272Y491866D03*
X380210Y491077D03*
X385169Y490563D03*
X329156Y545492D03*
Y540492D03*
Y535492D03*
Y530492D03*
Y525492D03*
Y520492D03*
Y515492D03*
Y560492D03*
Y555492D03*
Y550492D03*
X405169Y490563D03*
X410169D03*
X415169D03*
X420169D03*
X425169D03*
X430169D03*
X435169D03*
X440169D03*
X445146Y490850D03*
X450083Y491640D03*
X390169Y490563D03*
X395169D03*
X400169D03*
X505500Y464400D03*
Y469200D03*
Y474000D03*
X509500Y450800D03*
Y446000D03*
Y441200D03*
X469832Y494799D03*
X474769Y495589D03*
X455020Y492430D03*
X459958Y493219D03*
X464895Y494009D03*
X497636Y515532D03*
Y520532D03*
Y525532D03*
Y530532D03*
Y535532D03*
Y540532D03*
Y545532D03*
Y550532D03*
Y555532D03*
Y560532D03*
X502550Y565366D03*
X507550D03*
X512550D03*
X570234Y298026D03*
X572634Y293526D03*
X571300Y414800D03*
X567200Y407700D03*
X572062Y384378D03*
X527742Y425481D03*
X522942D03*
X518142D03*
X527742Y432481D03*
X522942D03*
X518142D03*
X529500Y471500D03*
X551400Y437800D03*
X545900D03*
X539800Y437900D03*
X517550Y565366D03*
X522550D03*
X527550D03*
X532550D03*
X537550D03*
X542550D03*
X547550D03*
X552550D03*
X557550D03*
X562550D03*
X567550D03*
X572550D03*
X591446Y6545D03*
X596446D03*
X601446D03*
X606446D03*
X611446D03*
X616446D03*
X621446D03*
X636446D03*
X631446D03*
X626446D03*
X576797Y113877D03*
X582554Y116361D03*
X575134Y298026D03*
X577534Y293526D03*
X580034Y298026D03*
X580900Y414800D03*
X576100D03*
X632150Y389100D03*
X576862Y384378D03*
X581087Y379569D03*
X576287D03*
X581692Y384378D03*
X628113Y428617D03*
X623313D03*
X618513D03*
X613713D03*
X605534Y480027D03*
X635000Y427784D03*
X619600Y446100D03*
X629200D03*
X624400D03*
X577550Y565366D03*
X582550D03*
X587550D03*
X592550D03*
X597550D03*
X602550D03*
X607550D03*
X612550D03*
X617550D03*
X622550D03*
X627550D03*
X632550D03*
X641446Y6545D03*
X646446D03*
X651446D03*
X696446D03*
X691446D03*
X661446D03*
X656446D03*
X686446D03*
X681446D03*
X676446D03*
X671446D03*
X666446D03*
X655964Y52248D03*
X675136Y268500D03*
X637705Y298765D03*
X642705D03*
X659977Y323082D03*
X664731Y324099D03*
X660115Y351977D03*
Y356777D03*
X664731Y343299D03*
X655500Y360000D03*
X660115Y361577D03*
X664731Y338499D03*
Y333699D03*
Y328899D03*
X659977Y342282D03*
Y332682D03*
Y347082D03*
Y337482D03*
Y327882D03*
X696900Y337800D03*
X697500Y358200D03*
X637705Y303765D03*
X642705D03*
X674700Y306300D03*
X679500D03*
Y311100D03*
X674700D03*
X679500Y315900D03*
X674700D03*
X665520Y307707D03*
Y312507D03*
X654642D03*
X654488Y317417D03*
X660100Y307500D03*
X654642Y307707D03*
X665478Y317527D03*
X684400Y400100D03*
X637550Y389050D03*
X655532Y425245D03*
X658032Y420245D03*
X653032D03*
X653200Y408800D03*
X694950Y477850D03*
Y473050D03*
X688500Y484400D03*
X675700Y468000D03*
Y463500D03*
X675400Y472300D03*
X659000Y428900D03*
X652200Y429100D03*
X639120Y462230D03*
X688500Y488600D03*
X637550Y565366D03*
X642550D03*
X647550D03*
X652550D03*
X657550D03*
X662550D03*
X667550D03*
X672550D03*
X677550D03*
X682550D03*
X687550D03*
X692550D03*
X697550D03*
X701446Y6545D03*
X742200Y340800D03*
Y345600D03*
X737400Y340800D03*
Y345600D03*
X732600Y331200D03*
Y336000D03*
Y340800D03*
Y355200D03*
Y350400D03*
Y345600D03*
X701100Y315900D03*
X705900D03*
X701100Y311100D03*
X705900D03*
Y306300D03*
X701100D03*
X714600Y338900D03*
Y348500D03*
Y343700D03*
X709800Y348500D03*
Y343700D03*
X706500Y337800D03*
X701700D03*
X707100Y358200D03*
X702300D03*
X704115Y414466D03*
Y409666D03*
Y404866D03*
Y400066D03*
X722100Y368300D03*
X717300D03*
X712500D03*
X742200Y380400D03*
Y370800D03*
Y375600D03*
X728700Y381000D03*
Y376200D03*
Y371400D03*
X722100Y363500D03*
X717300D03*
X712500D03*
X705900Y386900D03*
X711000Y395100D03*
X710900Y386800D03*
X706000Y395100D03*
X725247Y458974D03*
X724422Y464139D03*
X724400Y485200D03*
Y480400D03*
Y475600D03*
X740900Y476400D03*
Y469400D03*
Y461900D03*
X704340Y468062D03*
X705400Y477400D03*
X724400Y490200D03*
X702550Y565366D03*
X707550D03*
X712550D03*
X717550D03*
X722550D03*
X727550D03*
X732550D03*
X737550D03*
X742550D03*
X747550D03*
X752550D03*
X757550D03*
X821272Y49340D03*
Y44340D03*
Y39340D03*
Y34340D03*
Y29340D03*
Y24340D03*
Y19340D03*
Y14340D03*
Y9340D03*
X815364Y5500D03*
X810364D03*
X805364D03*
X800364D03*
X795364D03*
X790364D03*
X785364D03*
X780364D03*
X775364D03*
X770364D03*
X765364D03*
X821272Y114340D03*
Y109340D03*
Y104340D03*
Y99340D03*
Y94340D03*
Y89340D03*
Y84340D03*
Y79340D03*
Y74340D03*
Y69340D03*
Y64340D03*
Y59340D03*
Y54340D03*
Y174340D03*
Y169340D03*
Y164340D03*
Y159340D03*
Y154340D03*
Y149340D03*
Y144340D03*
Y139340D03*
Y134340D03*
Y129340D03*
Y124340D03*
Y119340D03*
Y234340D03*
Y229340D03*
Y224340D03*
Y219340D03*
Y214340D03*
Y209340D03*
Y204340D03*
Y199340D03*
Y194340D03*
Y189340D03*
Y184340D03*
Y179340D03*
X771083Y211784D03*
X821272Y299340D03*
Y294340D03*
Y289340D03*
Y284340D03*
Y279340D03*
Y274340D03*
Y269340D03*
Y264340D03*
Y259340D03*
Y254340D03*
Y249340D03*
Y244340D03*
Y239340D03*
Y359340D03*
Y354340D03*
Y349340D03*
Y344340D03*
Y339340D03*
Y334340D03*
Y329340D03*
Y324340D03*
Y319340D03*
Y314340D03*
Y309340D03*
Y304340D03*
Y424340D03*
Y419340D03*
Y414340D03*
Y409340D03*
Y404340D03*
Y399340D03*
Y394340D03*
Y389340D03*
Y384340D03*
Y379340D03*
Y374340D03*
Y369340D03*
Y364340D03*
Y484340D03*
Y479340D03*
Y474340D03*
Y469340D03*
Y464340D03*
Y459340D03*
Y454340D03*
Y449340D03*
Y444340D03*
Y439340D03*
Y434340D03*
Y429340D03*
Y504340D03*
Y509340D03*
Y514340D03*
Y519340D03*
Y524340D03*
Y529340D03*
Y549340D03*
Y544340D03*
Y539340D03*
Y534340D03*
Y499340D03*
Y494340D03*
Y489340D03*
X762550Y565366D03*
X767550D03*
X772550D03*
X777550D03*
X782550D03*
X787550D03*
X792550D03*
X797550D03*
X802550D03*
X807550D03*
X812550D03*
X817550D03*
X821272Y559340D03*
Y554340D03*
X1019575Y378703D03*
G54D20*
X98425Y472441D03*
X137795D03*
X1019575Y182003D03*
G54D30*
G01X-34018Y-300855D02*
G02I-12000J0D01*
G01X-39168D02*
G02I-6850J0D01*
G01X-30018D02*
X-62018D01*
G01X-30018Y-316855D02*
Y-396855D01*
G01D02*
X1320682D01*
G01X-30018Y-352355D02*
X1320682D01*
G01X-46018Y-316855D02*
Y-284855D01*
G01X-30018Y-316855D02*
X1320682D01*
G01X533182D02*
Y-396855D01*
G01X670682Y-316855D02*
Y-396855D01*
G01X785682Y-316855D02*
Y-396855D01*
G01X953182Y-316855D02*
Y-396855D01*
G01X1123182Y-316855D02*
Y-396855D01*
G01X1320682Y-316855D02*
Y-396855D01*
G01X1348682Y-300855D02*
G02I-12000J0D01*
G01X1343532D02*
G02I-6850J0D01*
G01X1336682Y-316855D02*
Y-284855D01*
G01X1352682Y-300855D02*
X1320682D01*
G54D21*
X158267Y25708D03*
X145669D03*
X158267Y47362D03*
X145669D03*
X158267Y53267D03*
Y41456D03*
Y31614D03*
Y19803D03*
X145669D03*
Y31614D03*
Y41456D03*
Y53267D03*
X1019575Y322503D03*
G54D12*
X22550Y156750D03*
X54697Y165269D03*
X58697D03*
X59600Y152000D03*
X71200Y137200D03*
X52400Y237800D03*
X28455Y187767D03*
X28749Y191548D03*
X39301Y203166D03*
X33700Y230600D03*
X21910Y217500D03*
X22250Y223500D03*
X39416Y206616D03*
X65500Y237800D03*
X70500D03*
X75500D03*
X23800Y211200D03*
X27500D03*
X59700Y178600D03*
X68400Y177950D03*
X76800Y178200D03*
X46194Y179835D03*
X50194D03*
X39320Y213823D03*
X64000Y178400D03*
X72800Y178200D03*
X22150Y203550D03*
X26150Y230850D03*
X33759Y274180D03*
X37830D03*
X23100Y292200D03*
Y287700D03*
X56026Y256117D03*
X23100Y283200D03*
X22750Y275450D03*
X23500Y296700D03*
X68300Y292200D03*
X45650Y250280D03*
X49320D03*
X40290Y239814D03*
X35405Y239808D03*
X32469Y250280D03*
X37469D03*
X69143Y334598D03*
X47443Y334198D03*
X27947Y334066D03*
X37049Y302949D03*
X23100Y318500D03*
Y314000D03*
X52450Y333850D03*
X31450Y334050D03*
X74150Y334250D03*
X28000Y326500D03*
X24000Y301750D03*
X23400Y309500D03*
X67800Y318000D03*
X67700Y321500D03*
X58900Y334180D03*
X62325Y334068D03*
X37900Y334380D03*
X41325Y334268D03*
X57350Y387800D03*
X46900Y378233D03*
X26100Y378352D03*
X69300Y378800D03*
X31240Y393440D03*
X49700Y391000D03*
X54040Y399390D03*
X65500Y378800D03*
X43000Y378233D03*
X22000Y378352D03*
X53500Y403150D03*
X49700Y402000D03*
X50700Y378233D03*
X54800Y373600D03*
X29900Y378252D03*
X38200Y373800D03*
X34100D03*
X73100Y378700D03*
X60400Y373600D03*
X77200Y374000D03*
X65375Y392835D03*
X35800Y363400D03*
X40100D03*
X92300Y199400D03*
Y209400D03*
Y204400D03*
X90800Y217900D03*
X82600Y232000D03*
X78850Y221000D03*
X87300Y230650D03*
X92300Y190900D03*
X81300Y178050D03*
X85700Y178000D03*
X92300Y194900D03*
X78800Y205900D03*
X92300Y213900D03*
X89800Y178000D03*
X81000Y291700D03*
X80896Y286695D03*
X80688Y281695D03*
Y276695D03*
X93884Y242333D03*
X90238Y334391D03*
X78600Y321700D03*
X78700Y317400D03*
X102300Y329100D03*
X95245Y334043D03*
X80700Y309400D03*
X80600Y304600D03*
Y334580D03*
X84025Y334468D03*
X102400Y333900D03*
X106500D03*
X89895Y378426D03*
X83232Y399956D03*
X85795Y378426D03*
X102395Y373793D03*
X93695Y378426D03*
X81300Y374000D03*
X98295Y373793D03*
X106709Y383400D03*
X112023Y383013D03*
X78171Y363195D03*
X82171D03*
X99266Y362988D03*
X103266D03*
X104900Y412200D03*
X102679Y391150D03*
X112638Y391197D03*
X107582Y391266D03*
X102850Y452650D03*
X94488Y489888D03*
X191000Y110000D03*
X182100Y105500D03*
X155991Y110061D03*
X200550Y111350D03*
X152800Y113400D03*
X164020Y101127D03*
X158612Y126645D03*
X198202Y135298D03*
X145900Y136500D03*
X196963Y122029D03*
X184600Y137400D03*
X195400Y147200D03*
X195500Y142400D03*
X201139Y121630D03*
X172800Y141001D03*
X180300Y175400D03*
X145585Y132451D03*
X197100Y298800D03*
X162522Y331774D03*
X196600Y306800D03*
X250137Y36053D03*
X242610Y53714D03*
X229000Y95000D03*
X234450Y73000D03*
X245250Y98250D03*
X261102Y77900D03*
X248169Y74454D03*
X223994Y63225D03*
X242727Y63391D03*
X261499Y55353D03*
X257499D03*
X241750Y98250D03*
X238867Y63650D03*
X255300Y72600D03*
X234693Y57400D03*
X255154Y69177D03*
X233759Y64752D03*
X220228Y63651D03*
X245800Y279200D03*
X207600Y292400D03*
X204400Y288700D03*
X248900Y282932D03*
X259629Y281000D03*
X242351Y282900D03*
X228300Y280900D03*
X219400Y279400D03*
X262800Y277835D03*
X242400Y289700D03*
X242402Y286300D03*
X225500Y278900D03*
X222320Y277658D03*
X207500Y278400D03*
X204997Y280702D03*
X253575Y320167D03*
X235500Y320100D03*
X218500Y320200D03*
X222000Y310600D03*
X231700Y320100D03*
X249775Y320167D03*
X214700Y320200D03*
X212198Y328316D03*
X208648Y328452D03*
X261365Y324351D03*
X245943Y326300D03*
X246100Y329700D03*
X230400Y326200D03*
Y329600D03*
X253245Y329698D03*
X253154Y326227D03*
X241556Y340111D03*
X237483Y339988D03*
X230000Y336500D03*
X233400Y336600D03*
X218400Y326600D03*
X218300Y330000D03*
X230400Y348000D03*
X255500Y423361D03*
X237600Y390500D03*
X261581Y370979D03*
X256172Y409530D03*
X261996Y365663D03*
X263250Y423411D03*
X257996Y365663D03*
X259800Y423400D03*
X256900Y380900D03*
X312840Y42398D03*
X325378Y50351D03*
Y35351D03*
X310065Y32397D03*
X270000Y29000D03*
Y33500D03*
Y38000D03*
Y42500D03*
X281700Y52285D03*
X285500D03*
X267188Y55192D03*
X296385Y108227D03*
X285361Y78015D03*
X281761D03*
X289161Y58068D03*
X277514D03*
X308591Y68928D03*
X304591D03*
X308591Y73074D03*
X311182Y58692D03*
X283385Y100227D03*
X287385D03*
X319533Y114283D03*
X291385Y100227D03*
X295385D03*
X306196Y110209D03*
X310711Y113820D03*
X314772Y108292D03*
X300311Y60800D03*
X300385Y108227D03*
X311182Y62800D03*
X272937Y90362D03*
X266895Y100227D03*
X306280Y82574D03*
X283393Y92325D03*
X301280Y82574D03*
X272937Y85862D03*
X304591Y73074D03*
X318773Y108083D03*
X278039Y82185D03*
X279385Y100227D03*
X292030Y90574D03*
X292385Y108227D03*
X280298Y95556D03*
X296280Y82574D03*
X324026Y115936D03*
X321343Y122343D03*
X321051Y134028D03*
X304529Y118792D03*
X317700Y275400D03*
X270143Y276969D03*
X323681Y259023D03*
X319881D03*
X284498Y299976D03*
X299635Y292650D03*
X317600Y278800D03*
X319543Y290159D03*
X303032Y289900D03*
X268400Y281000D03*
X266406Y277835D03*
X299635Y288650D03*
X292225Y288267D03*
X297021Y346579D03*
X287350Y351200D03*
X319550Y347169D03*
X305147Y354706D03*
X316050Y342200D03*
X287350Y357700D03*
X322500Y353700D03*
X301500Y337500D03*
X320650Y336456D03*
X306060Y337640D03*
X310200Y337600D03*
X294250Y325000D03*
X277150Y332000D03*
X273165Y320351D03*
X280800Y325000D03*
X290750D03*
X280217Y350927D03*
X269365Y320351D03*
X325500Y325400D03*
X314241Y308459D03*
X314300Y311900D03*
X308180Y305200D03*
X305628Y320511D03*
X301628D03*
X325500Y321400D03*
X314400Y327851D03*
X314045Y302900D03*
X314500Y324251D03*
X319100Y330600D03*
X305628Y324511D03*
X324100Y307814D03*
X265365Y324351D03*
X281150Y332000D03*
X288536Y314764D03*
X275696Y314340D03*
X308398Y386479D03*
X304205Y382450D03*
X304398Y386479D03*
X292800Y363800D03*
X300019Y379524D03*
X296079D03*
X325200Y365100D03*
X312398Y386479D03*
X266300Y412100D03*
X270618Y385867D03*
X268004Y424361D03*
X323448Y405064D03*
X266500Y364000D03*
X325651Y439668D03*
X325629Y443510D03*
X328600Y114400D03*
X328711Y108053D03*
X335722Y94574D03*
X329722D03*
X374616Y172378D03*
X370061Y172433D03*
X355500Y144500D03*
X342000Y141600D03*
X331649Y126111D03*
X339049Y124238D03*
X335994Y126119D03*
X341913Y145049D03*
X374915Y176442D03*
X359969Y124510D03*
X349911Y136954D03*
X341757Y211056D03*
X337157Y206052D03*
X335701Y223995D03*
X352047Y220590D03*
X357546Y230354D03*
X360710Y231897D03*
X376306Y182715D03*
X351723Y178499D03*
X354143Y183439D03*
X362260Y184360D03*
X364169Y188366D03*
X366460Y191794D03*
X368558Y194540D03*
X379415Y194608D03*
X370570Y198219D03*
X371124Y178760D03*
X372517Y182362D03*
X380400Y287400D03*
X382000Y296500D03*
X384600Y285600D03*
X368714Y261134D03*
X339500Y260400D03*
X327868Y290125D03*
X365996Y287265D03*
Y272841D03*
X366169Y246591D03*
X370669D03*
X338650Y281350D03*
X361996Y272841D03*
X379000Y272600D03*
X384300Y291100D03*
X346900Y281300D03*
X343100D03*
X357996Y272841D03*
X328134Y252720D03*
X376633Y261543D03*
X340280Y253765D03*
X358096Y262268D03*
X341998Y256700D03*
X368610Y257299D03*
X376633Y256851D03*
X385887Y305222D03*
X381396Y302610D03*
X335400Y337400D03*
X345700Y349773D03*
X337600Y349600D03*
X339000Y344700D03*
X330000Y345800D03*
X335882Y309823D03*
X327400Y342600D03*
X386159Y337080D03*
X368050Y337200D03*
X370250Y347600D03*
X379148Y337184D03*
X384341Y315377D03*
X377324Y302844D03*
X360050Y337200D03*
X348600Y323900D03*
X359400Y347200D03*
X375148Y337184D03*
X382600Y337200D03*
X344000Y316000D03*
X346500Y302500D03*
X356550Y337200D03*
X348596Y337250D03*
X347750Y315850D03*
X352396Y337200D03*
X331026Y303354D03*
X328100Y331300D03*
X329364Y316949D03*
X364050Y337200D03*
X374250Y347600D03*
X359200Y315800D03*
X355200D03*
X360300Y323900D03*
X363400Y315800D03*
X344000Y388500D03*
X340375Y365944D03*
X331765Y386535D03*
X367450Y409955D03*
X338000Y421000D03*
X367350Y406455D03*
X360000Y410000D03*
X337592Y405027D03*
X327365Y433732D03*
X337900Y431200D03*
X448300Y337500D03*
X444100Y341000D03*
X444200Y337600D03*
X444100Y345000D03*
X440300Y337500D03*
X444959Y352053D03*
X389559Y337103D03*
X421500Y337500D03*
X427500D03*
X448431Y348737D03*
X416822Y347133D03*
X412381Y347149D03*
X435000Y347800D03*
X441000D03*
X433500Y337500D03*
X426464Y347078D03*
X397000Y337000D03*
X401700Y337350D03*
X392959Y337099D03*
X405921Y347159D03*
X430464Y347078D03*
X390550Y326820D03*
X405783Y339318D03*
X448500Y424000D03*
X445000Y422000D03*
X490877Y176547D03*
X510427Y176431D03*
X500302Y176489D03*
X490877Y189047D03*
Y185047D03*
Y180547D03*
X510427Y188931D03*
Y184931D03*
Y180431D03*
X500302Y188989D03*
Y184989D03*
Y180489D03*
X452300Y337500D03*
X468300D03*
X456550D03*
X464300D03*
X460800Y337562D03*
X460300Y333500D03*
X481359Y347727D03*
X467774Y362151D03*
X467100Y357500D03*
X464500Y347410D03*
X502138Y348500D03*
X476500Y347650D03*
X498138Y348500D03*
X506200Y358809D03*
X493200Y358800D03*
X498700Y359209D03*
X452600Y332700D03*
X462450Y358960D03*
X472463Y329837D03*
X468500Y347500D03*
X476200Y334900D03*
X506262Y348500D03*
X510138D03*
X479640Y334674D03*
X485100Y366800D03*
X490000Y363700D03*
X502850Y368500D03*
X503800Y382700D03*
X473900Y371800D03*
X485100Y363400D03*
X510200Y363209D03*
X506200D03*
X494400Y363800D03*
X499100Y363409D03*
X452500Y423500D03*
X510700Y367309D03*
X506700D03*
X489600Y367209D03*
X474200Y367500D03*
X457599Y419642D03*
X496300Y378935D03*
X489500Y371200D03*
X520552Y176373D03*
X557500Y231900D03*
X553500D03*
X549000D03*
X545000D03*
X520552Y188873D03*
Y184873D03*
Y180373D03*
X554717Y255796D03*
X550717D03*
X546217D03*
X542217D03*
X554975Y248209D03*
X550975D03*
X546475D03*
X542475D03*
X555865Y240638D03*
X551865D03*
X547365D03*
X543365D03*
X542627Y324049D03*
X546627D03*
X551127D03*
X555127D03*
X541278Y315738D03*
X545278D03*
X549778D03*
X553778D03*
X541221Y308771D03*
X545221D03*
X549721D03*
X553721D03*
X541193Y301280D03*
X545193D03*
X549693D03*
X553693D03*
X552200Y339300D03*
X556800D03*
X547225Y357997D03*
X547379Y338352D03*
X539900Y338300D03*
X534000Y338400D03*
X538225Y357997D03*
X555697Y356565D03*
X514000Y359209D03*
X514138Y348500D03*
X518138Y348350D03*
X525438Y350500D03*
X519263Y327092D03*
X538476Y334365D03*
X538436Y330918D03*
X534100Y342410D03*
X536200Y348300D03*
X540200D03*
X550100D03*
X546100D03*
X554685Y333410D03*
X547927Y342199D03*
X543646Y342347D03*
X539446D03*
X519629Y330448D03*
X521914Y332907D03*
X557411Y481025D03*
X554250Y457500D03*
X574250Y466900D03*
X545880Y485940D03*
X539040Y480090D03*
X562460Y457580D03*
X517125Y488975D03*
X629813Y27661D03*
X631864Y51848D03*
X632416Y31609D03*
X627603Y43523D03*
X627500Y19339D03*
X626786Y31227D03*
X635942Y97351D03*
X634400Y102000D03*
X630600D03*
X627500Y64500D03*
X629500Y61500D03*
X590537Y170119D03*
X589706Y174031D03*
X586912Y154495D03*
X586081Y158407D03*
X585145Y162809D03*
X584314Y166721D03*
X596233Y145667D03*
X595402Y149579D03*
X594466Y153981D03*
X593635Y157893D03*
X588901Y134308D03*
X588070Y138220D03*
X587134Y142622D03*
X586303Y146534D03*
X577699Y123469D03*
X576868Y127381D03*
X575932Y131783D03*
X575101Y135695D03*
X634169Y166500D03*
X618250Y162081D03*
X618400Y173443D03*
X617600Y134400D03*
X635852Y133715D03*
X589966Y210195D03*
X589135Y214107D03*
X588199Y218509D03*
X587368Y222421D03*
X585841Y194571D03*
X585010Y198483D03*
X584074Y202885D03*
X583243Y206797D03*
X581716Y178947D03*
X580885Y182859D03*
X579949Y187261D03*
X579118Y191173D03*
X588770Y178433D03*
X587939Y182345D03*
X627455Y185364D03*
X634000Y234200D03*
X630000D03*
X636363Y209944D03*
X632363D03*
X628363D03*
X624363D03*
X622400Y216750D03*
X598600Y247800D03*
Y253100D03*
X633800Y239600D03*
X629900Y239700D03*
X633800Y245700D03*
X629900Y245800D03*
X634100Y252000D03*
X629900D03*
X594025Y284017D03*
X618300Y288745D03*
X632750Y292195D03*
Y295641D03*
X594025Y280017D03*
X590050Y337950D03*
X590200Y334350D03*
X610750Y336850D03*
X594050Y301755D03*
X632750Y330854D03*
Y334300D03*
X618300Y327654D03*
X632900Y344950D03*
X612300Y356850D03*
X608500Y315000D03*
X634000Y306300D03*
X631800Y316137D03*
X603650Y315500D03*
X594292Y362291D03*
X625000Y361700D03*
X590350Y323011D03*
X629250Y310491D03*
Y306491D03*
X626405Y314991D03*
X629250Y344900D03*
Y348900D03*
X623063Y357337D03*
X602649Y349033D03*
X594400Y357000D03*
Y353000D03*
X597450Y324750D03*
Y320750D03*
X627020Y393364D03*
X598152Y370130D03*
X629770Y369320D03*
X594200Y390400D03*
X629400Y414324D03*
X584280Y424030D03*
X598023Y383081D03*
X624200Y372500D03*
X620260Y389940D03*
X589394Y384572D03*
X589391Y378202D03*
X627140Y381353D03*
X631140D03*
X630000Y464900D03*
X626300D03*
X577330Y464430D03*
X599900Y438300D03*
X587890Y426720D03*
X581020Y471890D03*
X574667Y479799D03*
X577300Y460300D03*
X588400Y469450D03*
X634050Y469200D03*
X588663Y460037D03*
X581250Y480550D03*
X585420Y456480D03*
X633676Y460080D03*
X617000Y468700D03*
X588030Y430795D03*
X620600Y458500D03*
X652551Y40716D03*
X656450Y28000D03*
X655914Y39932D03*
X667149Y23411D03*
X656300Y20100D03*
X660200Y20200D03*
X647216Y31601D03*
X667900Y40800D03*
X643816Y31573D03*
X643103Y13803D03*
X664301Y40104D03*
Y49998D03*
X638103Y13100D03*
X640416Y31609D03*
X647103Y13964D03*
X694365Y98458D03*
Y94458D03*
Y90958D03*
Y86958D03*
X686279Y98494D03*
Y94494D03*
Y90994D03*
Y86994D03*
X678225Y98496D03*
Y94496D03*
Y90996D03*
Y86996D03*
X670146Y98505D03*
Y94505D03*
Y91005D03*
Y87005D03*
X662047Y98539D03*
Y94539D03*
Y91039D03*
Y87039D03*
X654037Y98708D03*
Y94708D03*
Y91208D03*
Y87208D03*
X637003Y68809D03*
X648207Y70750D03*
X654330Y113385D03*
X688976D03*
X646643Y97859D03*
X644100Y111811D03*
X668100Y56100D03*
X651564Y52638D03*
X644500Y65759D03*
X657480Y113385D03*
X678189Y108784D03*
X689049Y109487D03*
X669500Y108400D03*
X640600Y111600D03*
X641003Y68809D03*
X654330Y154330D03*
X657480Y151219D03*
X663778Y166928D03*
X673227Y157479D03*
X673229Y166929D03*
Y173228D03*
X670080Y148030D03*
X679526Y144880D03*
X660629Y138584D03*
Y141732D03*
X688978Y135435D03*
X682679D03*
X676379D03*
X695274Y135431D03*
X698425Y129134D03*
X663778Y160629D03*
Y154330D03*
Y135431D03*
X692124D03*
X673227Y144880D03*
X685825Y138581D03*
X679526D03*
X673227D03*
X666928D03*
X648032Y129134D03*
X657480Y122834D03*
X698425Y135433D03*
Y138582D03*
X692125D03*
X682677Y148031D03*
X688976D03*
X695275D03*
X682677Y154330D03*
X688976D03*
X695275D03*
Y160629D03*
X688976D03*
X682677Y160630D03*
X679527Y163779D03*
X695275Y166929D03*
X688976D03*
X682677D03*
X695275Y173228D03*
X688976D03*
X682677D03*
X654330Y170078D03*
X648031Y163779D03*
X654330D03*
X651181Y157480D03*
X670078Y154330D03*
X644882Y157480D03*
X666929Y125984D03*
X657480Y129134D03*
X651181Y151181D03*
X698425Y116535D03*
X648059Y151191D03*
X685827Y125985D03*
X676377Y116536D03*
X663778Y176377D03*
Y173227D03*
Y170078D03*
X670078Y166928D03*
Y173227D03*
X654330Y176377D03*
X639108Y167800D03*
X648057Y141721D03*
X648032Y135434D03*
Y122835D03*
X660629Y116536D03*
X666929Y116535D03*
X698426Y122835D03*
X692148Y129119D03*
X670116Y132283D03*
X673229Y125985D03*
X679528D03*
X660629Y170078D03*
Y173227D03*
X654330Y157480D03*
X651181Y154330D03*
X673229Y170079D03*
X679527Y173229D03*
X692126Y141732D03*
X698425D03*
X679527Y148031D03*
X685826D03*
X692126D03*
X698425D03*
X679527Y154330D03*
X685826D03*
X692126D03*
X698425D03*
Y160629D03*
X692126D03*
X685826D03*
X679527D03*
X698425Y166929D03*
X692126D03*
X685826D03*
X679527D03*
X698425Y173228D03*
X692126D03*
X685826D03*
X670078Y170078D03*
X654330Y173228D03*
X651181Y166929D03*
X676376Y132281D03*
X666929Y129134D03*
X660630Y160630D03*
X640775Y156218D03*
X648031Y157480D03*
X663779Y151181D03*
X666929Y148031D03*
X663779Y132283D03*
X663778Y144883D03*
Y138584D03*
X651181Y141732D03*
Y132283D03*
Y122834D03*
X644882Y154331D03*
X637952Y142515D03*
X640500Y125000D03*
X660629Y144883D03*
X657481Y132284D03*
X670078Y151181D03*
X637343Y171335D03*
Y174835D03*
X657480Y154330D03*
X644882Y173228D03*
Y176378D03*
Y170078D03*
X648031D03*
X670078Y157480D03*
X673228Y148031D03*
X692126Y125984D03*
X685827Y116535D03*
X670079Y125985D03*
X682678D03*
X676378D03*
X688977D03*
X676378Y119686D03*
X666929Y119685D03*
X663780Y125985D03*
X657479Y116536D03*
X654330Y116535D03*
Y119685D03*
Y122834D03*
X657480Y125984D03*
X654331D03*
X654330Y129134D03*
Y132283D03*
Y135433D03*
X651181D03*
X654330Y138582D03*
Y141732D03*
Y144882D03*
X651181D03*
X654330Y148031D03*
Y151181D03*
X679452Y209815D03*
X651181Y188976D03*
X679527Y182679D03*
Y188975D03*
X676379Y182678D03*
X692126Y182676D03*
Y185827D03*
Y179527D03*
X676379Y192126D03*
X670080Y182678D03*
X697069Y207157D03*
X663400Y234100D03*
X663200Y238100D03*
X682676Y179526D03*
Y188975D03*
X682677Y182677D03*
X682676Y185826D03*
X676377Y201574D03*
Y204723D03*
X685826Y198424D03*
X663778Y182676D03*
Y179526D03*
X654330Y182676D03*
X660629Y192125D03*
X666929D03*
X660630Y198425D03*
X676377Y198424D03*
X685826Y201574D03*
X682677Y192125D03*
X688976D03*
X698425D03*
X640931Y181102D03*
X646594Y210875D03*
X640584Y194127D03*
X683913Y213313D03*
X695275Y198425D03*
X692125Y198423D03*
X686352Y207200D03*
X651181Y192125D03*
X663779D03*
X657480D03*
X670078D03*
X654330Y185826D03*
Y179526D03*
X685826Y192125D03*
X692125D03*
X667353Y233486D03*
X640363Y209944D03*
X638479Y230640D03*
X674023Y213815D03*
X640509Y177600D03*
X674172Y210095D03*
X679400Y213300D03*
X679527Y198424D03*
X697149Y219742D03*
X692949D03*
X695600Y240354D03*
X682700D03*
X695625Y282250D03*
X669125Y280405D03*
X663000Y249200D03*
X663100Y252700D03*
X674841Y262854D03*
X695383Y266855D03*
X644153Y278745D03*
X660400Y271900D03*
X678500Y240324D03*
X691100Y240354D03*
X686900D03*
X668600Y242800D03*
X669450Y284900D03*
X695600Y244354D03*
X695375Y260875D03*
X637500Y362400D03*
X680300Y384900D03*
X662306Y365477D03*
X657673Y365400D03*
X672281Y378883D03*
X693500Y373300D03*
X694765Y406915D03*
X685750Y419460D03*
X642900Y395400D03*
X674150Y415380D03*
X654770Y401166D03*
X645970Y399130D03*
X669031Y388383D03*
X665031D03*
X653360Y386210D03*
X680700Y378200D03*
X687150Y385550D03*
X675031Y389383D03*
X653007Y382828D03*
X658601Y401800D03*
X673900Y418880D03*
X637500Y365900D03*
X672800Y438832D03*
X696950Y441400D03*
X667414Y431956D03*
X692200Y428700D03*
X681540Y429640D03*
X678700Y440950D03*
X671640Y454410D03*
X683250Y437813D03*
X710378Y100399D03*
Y96399D03*
Y92899D03*
Y88899D03*
X702391Y98510D03*
Y94510D03*
Y91010D03*
Y87010D03*
X728788Y88540D03*
X725295Y88609D03*
X752853Y100900D03*
X722673Y105444D03*
X736785Y110185D03*
X737800Y106525D03*
X717197Y109646D03*
X726100Y107200D03*
X734709Y106595D03*
X731000Y106315D03*
X734212Y109995D03*
X725943Y100147D03*
X744833Y78995D03*
X754572Y86923D03*
X754528Y83228D03*
X745100Y97500D03*
X699563Y108815D03*
X719010Y107281D03*
X707649Y110002D03*
X710517Y106823D03*
X750773Y74636D03*
X747919Y76667D03*
X720744Y92427D03*
X704849Y107385D03*
X733069Y166930D03*
X704725Y135434D03*
X707874Y141732D03*
X701574Y138582D03*
X701575Y135433D03*
X711023Y132283D03*
X704724D03*
X717322Y129133D03*
X726770Y166930D03*
Y173229D03*
X701574Y148031D03*
X707873D03*
X701574Y154330D03*
X707873D03*
Y160629D03*
X701574D03*
X707873Y166929D03*
X701574D03*
X707873Y173228D03*
X701574D03*
X711023Y122834D03*
X717322D03*
X723622D03*
X711023Y141732D03*
X743452Y151815D03*
X714172Y173227D03*
Y144880D03*
Y151180D03*
X717322Y144880D03*
Y151180D03*
X714172Y163778D03*
Y157479D03*
X717322Y163778D03*
Y157479D03*
Y166928D03*
X720472Y173228D03*
Y148031D03*
Y141732D03*
Y160629D03*
Y154330D03*
X720471Y166928D03*
X717322Y141731D03*
X758050Y164050D03*
X704725Y122835D03*
X720472Y135433D03*
X729921Y157480D03*
X739952Y120649D03*
X740952Y126815D03*
X707874Y116535D03*
X743100Y114700D03*
X737352Y145885D03*
X726771Y122835D03*
X729921Y122834D03*
X737702Y128565D03*
X729921Y132283D03*
Y129134D03*
X711023Y116535D03*
X726771Y163779D03*
X741754Y134617D03*
X729921Y135433D03*
X739622Y137008D03*
X729921Y138582D03*
Y144882D03*
X714173Y116535D03*
X717322D03*
X707873Y129133D03*
X720473Y116536D03*
X704725D03*
X704724Y148031D03*
Y154330D03*
Y160629D03*
Y166929D03*
Y173228D03*
X714173Y122834D03*
X720472D03*
X741077Y159790D03*
X757471Y148193D03*
X723621Y148031D03*
Y154330D03*
Y160629D03*
Y166929D03*
Y173228D03*
X707874Y122835D03*
X723621Y135433D03*
Y129133D03*
Y141732D03*
X701575Y122835D03*
X714173Y141732D03*
X723622Y116535D03*
X704723Y129133D03*
X701574D03*
X711022D03*
X714172D03*
X729921Y125984D03*
X711023Y173228D03*
X741952Y173115D03*
X738352Y174615D03*
X729920Y176378D03*
Y173229D03*
X736219Y170079D03*
X733070D03*
X746750Y157700D03*
X729921Y148031D03*
Y141732D03*
Y163779D03*
X750550Y135200D03*
X729921Y160629D03*
X701575Y116536D03*
X729921Y154330D03*
X717322Y182676D03*
X711024Y188976D03*
X701575Y182676D03*
X711022Y185825D03*
X701575Y185827D03*
Y179527D03*
X726770Y179528D03*
Y185827D03*
X743200Y227900D03*
X726770Y192126D03*
X730694Y224473D03*
X726656Y235244D03*
X711022Y179526D03*
X714172D03*
X722523Y221315D03*
X720437Y185829D03*
X720472Y179527D03*
Y192125D03*
X711022Y182676D03*
X704724Y192125D03*
X711024D03*
X730737Y235199D03*
X724465Y224741D03*
X714620Y221041D03*
X743460Y231900D03*
X701574Y192125D03*
X707873D03*
X714173D03*
X723621D03*
Y185826D03*
Y179527D03*
X715467Y210507D03*
X725009Y213292D03*
X739852Y195915D03*
X737832Y202664D03*
X729920Y188977D03*
X739752Y199615D03*
X738416Y190551D03*
X729920Y182678D03*
X745485Y197673D03*
Y201673D03*
X740352Y180115D03*
X729920Y185827D03*
X724776Y209963D03*
X743752Y187115D03*
X742502Y182715D03*
X742252Y177015D03*
X737315Y177952D03*
X733070Y179527D03*
X720819Y209800D03*
X729246Y209941D03*
X736272Y208181D03*
X729136Y206654D03*
X738839Y206080D03*
X733565Y210184D03*
X729920Y192126D03*
X720357Y207104D03*
X714173Y198425D03*
X729921Y179527D03*
X720471Y198424D03*
X731915Y206310D03*
X738952Y184215D03*
X744052Y193784D03*
X701574Y198424D03*
X711023Y198425D03*
X704724D03*
X717322D03*
X707873Y198424D03*
X723621D03*
X704724Y201574D03*
X706737Y205505D03*
X705336Y208437D03*
X711310Y207023D03*
X714173Y201574D03*
X718330Y205172D03*
X704708Y264647D03*
X751878Y276817D03*
X749620Y273620D03*
X707574Y276558D03*
X712720Y240976D03*
X754227Y297611D03*
X739300Y287611D03*
X751693Y255540D03*
X743507Y251685D03*
X747558Y247274D03*
X759558Y241027D03*
Y247274D03*
X731300Y287611D03*
X735300D03*
X731318Y283571D03*
X735318D03*
X731155Y279636D03*
X739318Y283571D03*
X734638Y275696D03*
X751693Y259540D03*
X755693D03*
X704708Y256647D03*
Y252647D03*
X753560Y273780D03*
X704708Y260647D03*
X751133Y313984D03*
X754227Y301111D03*
X705320Y420610D03*
X735570Y424760D03*
X721380Y423930D03*
X739680Y423900D03*
X700200Y388200D03*
Y384800D03*
X718110Y442960D03*
X708355Y454712D03*
X701120Y430620D03*
X719920Y429700D03*
X743480Y439080D03*
X710200Y441200D03*
X706120Y441410D03*
X729870Y451300D03*
X740900Y456400D03*
X700855Y426719D03*
X799250Y71125D03*
X772107Y83046D03*
X799493Y93250D03*
X761650Y89937D03*
X771610Y93040D03*
X799500Y106000D03*
X781000Y88000D03*
Y84200D03*
X788287Y86087D03*
X768250Y106300D03*
X768100Y109700D03*
X763560Y59820D03*
X767359Y82076D03*
X782500Y134283D03*
X773000Y119600D03*
X776600D03*
X794500Y134283D03*
X785000Y158900D03*
X760600Y173700D03*
X804320Y134300D03*
X804400Y175000D03*
X760800Y169550D03*
X769600Y164200D03*
X765200Y135750D03*
X786500Y134283D03*
X763050Y154100D03*
X761400Y160050D03*
X764600Y141500D03*
X768700Y129800D03*
X768900Y134800D03*
X760715Y210200D03*
X804412Y185332D03*
X800612Y185432D03*
X760715Y201700D03*
Y214200D03*
X790000Y224700D03*
X760715Y197200D03*
X764550Y182900D03*
X764750Y179300D03*
X761550Y180500D03*
X786400Y179000D03*
X779200Y178650D03*
X790714Y237308D03*
X801618Y210116D03*
Y214116D03*
X795498Y246171D03*
X793912Y297020D03*
X793837Y283696D03*
X781640Y278660D03*
X786006Y283383D03*
X781640Y282160D03*
X793837Y291696D03*
X805254Y263886D03*
X761484Y255581D03*
Y251581D03*
X780837Y240885D03*
X774637Y267746D03*
X770637D03*
X761638Y259635D03*
X774637Y259746D03*
Y263746D03*
X793837Y279636D03*
Y275696D03*
X780837Y267826D03*
X784837Y263891D03*
Y259951D03*
X793852Y256011D03*
Y252076D03*
X793837Y271761D03*
Y267826D03*
Y263696D03*
X774657Y255999D03*
X765638Y255635D03*
X774637Y251876D03*
X784837Y271761D03*
Y267826D03*
X793837Y287696D03*
X780837Y271761D03*
X801853Y300515D03*
X767890Y273380D03*
X763292Y287630D03*
X786610Y321340D03*
X786300Y309900D03*
X761520Y339110D03*
X765764Y326844D03*
X801728Y304572D03*
X776497Y338392D03*
X775672Y350204D03*
X782770Y321200D03*
X1019575Y547303D03*
G54D31*
G01X121778Y-377522D02*
X122652Y-376647D01*
X123307Y-375189D01*
X123744Y-373146D01*
X123307Y-371397D01*
X122434Y-370230D01*
X120905Y-369355D01*
X115010D01*
Y-386855D01*
X122215D01*
X123744Y-385689D01*
X124617Y-383938D01*
X125054Y-381897D01*
X124617Y-379855D01*
X123307Y-378105D01*
X121778Y-377522D01*
X115010D01*
G01X134475Y-386855D02*
Y-375189D01*
G01Y-377522D02*
X135567Y-376355D01*
X136659Y-375480D01*
X138187Y-375189D01*
X139278Y-375480D01*
X140589Y-376355D01*
G01X150447Y-392105D02*
X151757Y-392688D01*
X153504Y-392105D01*
X154595Y-390939D01*
X155469Y-389480D01*
X156778Y-384814D01*
X159617Y-375189D01*
G01X152630D02*
X156778Y-384814D01*
G01X176025Y-376647D02*
X174497Y-375480D01*
X173187Y-375189D01*
X171440Y-375772D01*
X170130Y-376938D01*
X169257Y-378980D01*
X169038Y-381022D01*
X169257Y-383064D01*
X170130Y-384814D01*
X171440Y-386272D01*
X173187Y-386855D01*
X174715Y-386272D01*
X176025Y-385105D01*
G01X186757Y-378980D02*
X193744D01*
X193089Y-376938D01*
X191997Y-375772D01*
X190469Y-375189D01*
X188940Y-375480D01*
X187630Y-376355D01*
X186757Y-378397D01*
X186320Y-380147D01*
Y-381897D01*
X186757Y-383647D01*
X187849Y-385397D01*
X189159Y-386563D01*
X190687Y-386855D01*
X192215Y-386272D01*
X193744Y-384522D01*
G01X229835Y-370814D02*
X228525Y-369938D01*
X226997Y-369355D01*
X225250D01*
X223285Y-370230D01*
X221757Y-371688D01*
X220665Y-373439D01*
X219792Y-376355D01*
X219573Y-378980D01*
X220010Y-381605D01*
X220665Y-383355D01*
X221975Y-385105D01*
X223504Y-386272D01*
X225032Y-386855D01*
X226560D01*
X228089Y-386272D01*
X229399Y-385397D01*
X230491Y-384231D01*
G01X246462Y-386855D02*
Y-375189D01*
G01Y-377230D02*
X245589Y-376064D01*
X244278Y-375480D01*
X242750Y-375189D01*
X241222Y-375772D01*
X239912Y-376938D01*
X239038Y-378688D01*
X238602Y-381022D01*
X239038Y-383355D01*
X239912Y-385105D01*
X241222Y-386272D01*
X242750Y-386855D01*
X244278Y-386563D01*
X245589Y-385689D01*
X246462Y-384522D01*
G01X256320Y-386855D02*
Y-375189D01*
G01Y-378105D02*
X257194Y-376647D01*
X258504Y-375480D01*
X260250Y-375189D01*
X261778Y-375480D01*
X263089Y-376647D01*
X263744Y-378688D01*
Y-386855D01*
G01X272947Y-392105D02*
X274257Y-392688D01*
X276004Y-392105D01*
X277095Y-390939D01*
X277969Y-389480D01*
X279278Y-384814D01*
X282117Y-375189D01*
G01X275130D02*
X279278Y-384814D01*
G01X295032Y-386855D02*
X293722Y-386563D01*
X292412Y-385397D01*
X291538Y-383355D01*
X291102Y-381022D01*
X291538Y-378688D01*
X292412Y-376647D01*
X293722Y-375480D01*
X295032Y-375189D01*
X296342Y-375480D01*
X297652Y-376647D01*
X298525Y-378688D01*
X298744Y-381022D01*
X298525Y-383355D01*
X297652Y-385397D01*
X296342Y-386563D01*
X295032Y-386855D01*
G01X308820D02*
Y-375189D01*
G01Y-378105D02*
X309694Y-376647D01*
X311004Y-375480D01*
X312750Y-375189D01*
X314278Y-375480D01*
X315589Y-376647D01*
X316244Y-378688D01*
Y-386855D01*
G01X342947Y-384522D02*
X344694Y-385980D01*
X346659Y-386855D01*
X348405D01*
X350152Y-385980D01*
X351462Y-384522D01*
X352117Y-382480D01*
X351680Y-380439D01*
X350589Y-378688D01*
X348624Y-377522D01*
X346004Y-376938D01*
X344475Y-375772D01*
X343820Y-373730D01*
X344257Y-371688D01*
X345349Y-370230D01*
X346877Y-369355D01*
X348405D01*
X349934Y-369938D01*
X351244Y-371397D01*
G01X369835Y-370814D02*
X368525Y-369938D01*
X366997Y-369355D01*
X365250D01*
X363285Y-370230D01*
X361757Y-371688D01*
X360665Y-373439D01*
X359792Y-376355D01*
X359573Y-378980D01*
X360010Y-381605D01*
X360665Y-383355D01*
X361975Y-385105D01*
X363504Y-386272D01*
X365032Y-386855D01*
X366560D01*
X368089Y-386272D01*
X369399Y-385397D01*
X370491Y-384231D01*
G01X387335Y-370814D02*
X386025Y-369938D01*
X384497Y-369355D01*
X382750D01*
X380785Y-370230D01*
X379257Y-371688D01*
X378165Y-373439D01*
X377292Y-376355D01*
X377073Y-378980D01*
X377510Y-381605D01*
X378165Y-383355D01*
X379475Y-385105D01*
X381004Y-386272D01*
X382532Y-386855D01*
X384060D01*
X385589Y-386272D01*
X386899Y-385397D01*
X387991Y-384231D01*
G01X210605Y-341855D02*
Y-324355D01*
X216282Y-338938D01*
X221959Y-324355D01*
Y-341855D01*
G01X233782D02*
X232472Y-341563D01*
X231162Y-340397D01*
X230288Y-338355D01*
X229852Y-336022D01*
X230288Y-333688D01*
X231162Y-331647D01*
X232472Y-330480D01*
X233782Y-330189D01*
X235092Y-330480D01*
X236402Y-331647D01*
X237275Y-333688D01*
X237494Y-336022D01*
X237275Y-338355D01*
X236402Y-340397D01*
X235092Y-341563D01*
X233782Y-341855D01*
G01X255212Y-324355D02*
Y-341855D01*
G01Y-339231D02*
X254339Y-340689D01*
X253028Y-341563D01*
X251500Y-341855D01*
X249754Y-341272D01*
X248444Y-339814D01*
X247570Y-338064D01*
X247352Y-336022D01*
X247570Y-333980D01*
X248444Y-332230D01*
X249754Y-330772D01*
X251500Y-330189D01*
X253028Y-330480D01*
X254120Y-331064D01*
X255212Y-332230D01*
G01X265507Y-333980D02*
X272494D01*
X271839Y-331938D01*
X270747Y-330772D01*
X269219Y-330189D01*
X267690Y-330480D01*
X266380Y-331355D01*
X265507Y-333397D01*
X265070Y-335147D01*
Y-336897D01*
X265507Y-338647D01*
X266599Y-340397D01*
X267909Y-341563D01*
X269437Y-341855D01*
X270965Y-341272D01*
X272494Y-339522D01*
G01X286282Y-341855D02*
Y-324355D01*
G01X566882Y-386855D02*
Y-369355D01*
X564262Y-372855D01*
G01Y-386855D02*
X569502D01*
G01X580234Y-379564D02*
X581762Y-377522D01*
X583072Y-376355D01*
X584819Y-375772D01*
X586347Y-376355D01*
X587439Y-377522D01*
X588312Y-379272D01*
X588530Y-381313D01*
X588312Y-383064D01*
X587439Y-384814D01*
X586128Y-386272D01*
X584600Y-386855D01*
X582854Y-386272D01*
X581325Y-384522D01*
X580452Y-381897D01*
X580234Y-378980D01*
X580670Y-375189D01*
X581325Y-373146D01*
X582417Y-371105D01*
X583945Y-369647D01*
X585474Y-369355D01*
X587002Y-369938D01*
X588094Y-371397D01*
G01X597079Y-383355D02*
X598388Y-385397D01*
X600135Y-386563D01*
X602100Y-386855D01*
X603847Y-386563D01*
X605594Y-385105D01*
X606685Y-383355D01*
X606904Y-381605D01*
X606467Y-379564D01*
X604939Y-378105D01*
X603410Y-377522D01*
X601445D01*
G01X603410D02*
X604720Y-376647D01*
X605812Y-375189D01*
X606249Y-373439D01*
X605812Y-371688D01*
X604720Y-370230D01*
X602755Y-369355D01*
X600790Y-369647D01*
X598825Y-370814D01*
G01X619382Y-386855D02*
Y-369355D01*
X616762Y-372855D01*
G01Y-386855D02*
X622002D01*
G01X632734Y-379564D02*
X634262Y-377522D01*
X635572Y-376355D01*
X637319Y-375772D01*
X638847Y-376355D01*
X639939Y-377522D01*
X640812Y-379272D01*
X641030Y-381313D01*
X640812Y-383064D01*
X639939Y-384814D01*
X638628Y-386272D01*
X637100Y-386855D01*
X635354Y-386272D01*
X633825Y-384522D01*
X632952Y-381897D01*
X632734Y-378980D01*
X633170Y-375189D01*
X633825Y-373146D01*
X634917Y-371105D01*
X636445Y-369647D01*
X637974Y-369355D01*
X639502Y-369938D01*
X640594Y-371397D01*
G01X553765Y-341855D02*
Y-324355D01*
X559005D01*
X560752Y-325230D01*
X562062Y-327272D01*
X562499Y-329605D01*
X562062Y-331938D01*
X560970Y-333688D01*
X559005Y-334564D01*
X553765D01*
G01X580435Y-325814D02*
X579125Y-324938D01*
X577597Y-324355D01*
X575850D01*
X573885Y-325230D01*
X572357Y-326688D01*
X571265Y-328439D01*
X570392Y-331355D01*
X570173Y-333980D01*
X570610Y-336605D01*
X571265Y-338355D01*
X572575Y-340105D01*
X574104Y-341272D01*
X575632Y-341855D01*
X577160D01*
X578689Y-341272D01*
X579999Y-340397D01*
X581091Y-339231D01*
G01X594878Y-332522D02*
X595752Y-331647D01*
X596407Y-330189D01*
X596844Y-328146D01*
X596407Y-326397D01*
X595534Y-325230D01*
X594005Y-324355D01*
X588110D01*
Y-341855D01*
X595315D01*
X596844Y-340689D01*
X597717Y-338938D01*
X598154Y-336897D01*
X597717Y-334855D01*
X596407Y-333105D01*
X594878Y-332522D01*
X588110D01*
G01X604082Y-347688D02*
X617182D01*
G01X623110Y-341855D02*
Y-324355D01*
X633154Y-341855D01*
Y-324355D01*
G01X645632Y-341855D02*
X643885Y-341563D01*
X642357Y-340397D01*
X641047Y-338647D01*
X640173Y-336605D01*
X639737Y-334272D01*
Y-331938D01*
X640173Y-329605D01*
X641047Y-327563D01*
X642357Y-325814D01*
X643885Y-324647D01*
X645632Y-324355D01*
X647378Y-324647D01*
X648907Y-325814D01*
X650217Y-327563D01*
X651091Y-329605D01*
X651527Y-331938D01*
Y-334272D01*
X651091Y-336605D01*
X650217Y-338647D01*
X648907Y-340397D01*
X647378Y-341563D01*
X645632Y-341855D01*
G01X696473Y-324355D02*
X701932Y-341855D01*
X707391Y-324355D01*
G01X723799Y-341855D02*
X715065D01*
Y-324355D01*
X723799D01*
G01X720305Y-332813D02*
X715065D01*
G01X732565Y-341855D02*
Y-324355D01*
X738024D01*
X739770Y-325230D01*
X740862Y-326397D01*
X741299Y-328730D01*
X740862Y-331064D01*
X739552Y-332522D01*
X738024Y-333397D01*
X732565D01*
G01X738024D02*
X741299Y-341855D01*
G01X754432Y-342438D02*
X753995Y-342147D01*
Y-341563D01*
X754432Y-341272D01*
X754869Y-341563D01*
Y-342147D01*
X754432Y-342438D01*
G01X728182Y-386855D02*
Y-369355D01*
X725562Y-372855D01*
G01Y-386855D02*
X730802D01*
G01X829579D02*
Y-369355D01*
X833945D01*
X835692Y-370230D01*
X837002Y-371397D01*
X838094Y-373146D01*
X838967Y-375189D01*
X839185Y-378105D01*
X838967Y-381022D01*
X838094Y-383064D01*
X837002Y-384814D01*
X835692Y-385980D01*
X833945Y-386855D01*
X829579D01*
G01X847515D02*
Y-369355D01*
X852974D01*
X854720Y-370230D01*
X855812Y-371397D01*
X856249Y-373730D01*
X855812Y-376064D01*
X854502Y-377522D01*
X852974Y-378397D01*
X847515D01*
G01X852974D02*
X856249Y-386855D01*
G01X866762Y-369355D02*
X872002D01*
G01X869382D02*
Y-386855D01*
G01X866762D02*
X872002D01*
G01X882515Y-369355D02*
Y-386855D01*
X891249D01*
G01X900015Y-369355D02*
Y-386855D01*
X908749D01*
G01X830015Y-324355D02*
Y-341855D01*
X838749D01*
G01X855812D02*
Y-330189D01*
G01Y-332230D02*
X854939Y-331064D01*
X853628Y-330480D01*
X852100Y-330189D01*
X850572Y-330772D01*
X849262Y-331938D01*
X848388Y-333688D01*
X847952Y-336022D01*
X848388Y-338355D01*
X849262Y-340105D01*
X850572Y-341272D01*
X852100Y-341855D01*
X853628Y-341563D01*
X854939Y-340689D01*
X855812Y-339522D01*
G01X864797Y-347105D02*
X866107Y-347688D01*
X867854Y-347105D01*
X868945Y-345939D01*
X869819Y-344480D01*
X871128Y-339814D01*
X873967Y-330189D01*
G01X866980D02*
X871128Y-339814D01*
G01X883607Y-333980D02*
X890594D01*
X889939Y-331938D01*
X888847Y-330772D01*
X887319Y-330189D01*
X885790Y-330480D01*
X884480Y-331355D01*
X883607Y-333397D01*
X883170Y-335147D01*
Y-336897D01*
X883607Y-338647D01*
X884699Y-340397D01*
X886009Y-341563D01*
X887537Y-341855D01*
X889065Y-341272D01*
X890594Y-339522D01*
G01X901325Y-341855D02*
Y-330189D01*
G01Y-332522D02*
X902417Y-331355D01*
X903509Y-330480D01*
X905037Y-330189D01*
X906128Y-330480D01*
X907439Y-331355D01*
G01X994432Y-386855D02*
X992685Y-386563D01*
X991157Y-385397D01*
X989847Y-383647D01*
X988973Y-381605D01*
X988537Y-379272D01*
Y-376938D01*
X988973Y-374605D01*
X989847Y-372563D01*
X991157Y-370814D01*
X992685Y-369647D01*
X994432Y-369355D01*
X996178Y-369647D01*
X997707Y-370814D01*
X999017Y-372563D01*
X999891Y-374605D01*
X1000327Y-376938D01*
Y-379272D01*
X999891Y-381605D01*
X999017Y-383647D01*
X997707Y-385397D01*
X996178Y-386563D01*
X994432Y-386855D01*
G01X996178Y-382188D02*
X998799Y-386855D01*
G01X1007129Y-369355D02*
Y-381897D01*
X1008002Y-384522D01*
X1009749Y-386272D01*
X1011932Y-386855D01*
X1014115Y-386272D01*
X1015862Y-384522D01*
X1016735Y-381897D01*
Y-369355D01*
G01X1026812D02*
X1032052D01*
G01X1029432D02*
Y-386855D01*
G01X1026812D02*
X1032052D01*
G01X1041910D02*
Y-369355D01*
X1051954Y-386855D01*
Y-369355D01*
G01X1069235Y-370814D02*
X1067925Y-369938D01*
X1066397Y-369355D01*
X1064650D01*
X1062685Y-370230D01*
X1061157Y-371688D01*
X1060065Y-373439D01*
X1059192Y-376355D01*
X1058973Y-378980D01*
X1059410Y-381605D01*
X1060065Y-383355D01*
X1061375Y-385105D01*
X1062904Y-386272D01*
X1064432Y-386855D01*
X1065960D01*
X1067489Y-386272D01*
X1068799Y-385397D01*
X1069891Y-384231D01*
G01X1081932Y-386855D02*
Y-378980D01*
X1077565Y-369355D01*
G01X1086299D02*
X1081932Y-378980D01*
G01X972129Y-341855D02*
Y-324355D01*
X976495D01*
X978242Y-325230D01*
X979552Y-326397D01*
X980644Y-328146D01*
X981517Y-330189D01*
X981735Y-333105D01*
X981517Y-336022D01*
X980644Y-338064D01*
X979552Y-339814D01*
X978242Y-340980D01*
X976495Y-341855D01*
X972129D01*
G01X991157Y-333980D02*
X998144D01*
X997489Y-331938D01*
X996397Y-330772D01*
X994869Y-330189D01*
X993340Y-330480D01*
X992030Y-331355D01*
X991157Y-333397D01*
X990720Y-335147D01*
Y-336897D01*
X991157Y-338647D01*
X992249Y-340397D01*
X993559Y-341563D01*
X995087Y-341855D01*
X996615Y-341272D01*
X998144Y-339522D01*
G01X1008657Y-339814D02*
X1009749Y-340980D01*
X1011277Y-341855D01*
X1012587D01*
X1013897Y-341272D01*
X1014770Y-340397D01*
X1015207Y-339231D01*
X1014989Y-337480D01*
X1014115Y-336605D01*
X1010185Y-334855D01*
X1009312Y-332813D01*
X1009749Y-331355D01*
X1010622Y-330480D01*
X1011932Y-330189D01*
X1013242Y-330480D01*
X1014552Y-331355D01*
G01X1029432Y-330189D02*
Y-341855D01*
G01Y-325522D02*
X1028995Y-325230D01*
Y-324647D01*
X1029432Y-324355D01*
X1029869Y-324647D01*
Y-325230D01*
X1029432Y-325522D01*
G01X1043875Y-346230D02*
X1045404Y-347397D01*
X1047150Y-347688D01*
X1048678Y-347397D01*
X1049989Y-345939D01*
X1050862Y-343897D01*
Y-330189D01*
G01Y-332522D02*
X1049989Y-331355D01*
X1048678Y-330480D01*
X1047150Y-330189D01*
X1045404Y-330772D01*
X1044312Y-331938D01*
X1043438Y-333980D01*
X1043002Y-336022D01*
X1043220Y-337772D01*
X1044094Y-339814D01*
X1045404Y-341272D01*
X1047150Y-341855D01*
X1048460Y-341563D01*
X1049989Y-340397D01*
X1050862Y-339231D01*
G01X1060720Y-341855D02*
Y-330189D01*
G01Y-333105D02*
X1061594Y-331647D01*
X1062904Y-330480D01*
X1064650Y-330189D01*
X1066178Y-330480D01*
X1067489Y-331647D01*
X1068144Y-333688D01*
Y-341855D01*
G01X1078657Y-333980D02*
X1085644D01*
X1084989Y-331938D01*
X1083897Y-330772D01*
X1082369Y-330189D01*
X1080840Y-330480D01*
X1079530Y-331355D01*
X1078657Y-333397D01*
X1078220Y-335147D01*
Y-336897D01*
X1078657Y-338647D01*
X1079749Y-340397D01*
X1081059Y-341563D01*
X1082587Y-341855D01*
X1084115Y-341272D01*
X1085644Y-339522D01*
G01X1096375Y-341855D02*
Y-330189D01*
G01Y-332522D02*
X1097467Y-331355D01*
X1098559Y-330480D01*
X1100087Y-330189D01*
X1101178Y-330480D01*
X1102489Y-331355D01*
G01X975710Y-2547D02*
Y9953D01*
X982840Y-2547D01*
Y9953D01*
G01X991675Y-2547D02*
X990745Y-2339D01*
X989815Y-1506D01*
X989195Y-47D01*
X988885Y1620D01*
X989195Y3286D01*
X989815Y4745D01*
X990745Y5578D01*
X991675Y5786D01*
X992605Y5578D01*
X993535Y4745D01*
X994155Y3286D01*
X994310Y1620D01*
X994155Y-47D01*
X993535Y-1506D01*
X992605Y-2339D01*
X991675Y-2547D01*
G01X1004075Y9953D02*
Y-2547D01*
G01X1001905Y5786D02*
X1006245D01*
G01X1014150Y3078D02*
X1019110D01*
X1018645Y4536D01*
X1017870Y5370D01*
X1016785Y5786D01*
X1015700Y5578D01*
X1014770Y4953D01*
X1014150Y3495D01*
X1013840Y2244D01*
Y995D01*
X1014150Y-255D01*
X1014925Y-1506D01*
X1015855Y-2339D01*
X1016940Y-2547D01*
X1018025Y-2130D01*
X1019110Y-881D01*
G01X1028875Y-2964D02*
X1028565Y-2755D01*
Y-2339D01*
X1028875Y-2130D01*
X1029185Y-2339D01*
Y-2755D01*
X1028875Y-2964D01*
G01Y2661D02*
X1028565Y2870D01*
Y3286D01*
X1028875Y3495D01*
X1029185Y3286D01*
Y2870D01*
X1028875Y2661D01*
G01X1038175Y-2547D02*
Y9953D01*
X1042050D01*
X1043290Y9328D01*
X1044065Y8495D01*
X1044375Y6828D01*
X1044065Y5161D01*
X1043135Y4120D01*
X1042050Y3495D01*
X1038175D01*
G01X1042050D02*
X1044375Y-2547D01*
G01X1051350Y3078D02*
X1056310D01*
X1055845Y4536D01*
X1055070Y5370D01*
X1053985Y5786D01*
X1052900Y5578D01*
X1051970Y4953D01*
X1051350Y3495D01*
X1051040Y2244D01*
Y995D01*
X1051350Y-255D01*
X1052125Y-1506D01*
X1053055Y-2339D01*
X1054140Y-2547D01*
X1055225Y-2130D01*
X1056310Y-881D01*
G01X1065145Y-2547D02*
Y8078D01*
X1065455Y9119D01*
X1066075Y9745D01*
X1067005Y9953D01*
X1067935Y9536D01*
X1068400Y8495D01*
G01X1066540Y4953D02*
X1063440D01*
G01X1076150Y3078D02*
X1081110D01*
X1080645Y4536D01*
X1079870Y5370D01*
X1078785Y5786D01*
X1077700Y5578D01*
X1076770Y4953D01*
X1076150Y3495D01*
X1075840Y2244D01*
Y995D01*
X1076150Y-255D01*
X1076925Y-1506D01*
X1077855Y-2339D01*
X1078940Y-2547D01*
X1080025Y-2130D01*
X1081110Y-881D01*
G01X1088705Y-2547D02*
Y5786D01*
G01Y4120D02*
X1089480Y4953D01*
X1090255Y5578D01*
X1091340Y5786D01*
X1092115Y5578D01*
X1093045Y4953D01*
G01X1115675Y9953D02*
Y-2547D01*
G01X1113505Y5786D02*
X1117845D01*
G01X1128075Y-2547D02*
X1127145Y-2339D01*
X1126215Y-1506D01*
X1125595Y-47D01*
X1125285Y1620D01*
X1125595Y3286D01*
X1126215Y4745D01*
X1127145Y5578D01*
X1128075Y5786D01*
X1129005Y5578D01*
X1129935Y4745D01*
X1130555Y3286D01*
X1130710Y1620D01*
X1130555Y-47D01*
X1129935Y-1506D01*
X1129005Y-2339D01*
X1128075Y-2547D01*
G01X1149465D02*
Y9953D01*
X1152565D01*
X1153805Y9328D01*
X1154735Y8495D01*
X1155510Y7245D01*
X1156130Y5786D01*
X1156285Y3703D01*
X1156130Y1620D01*
X1155510Y161D01*
X1154735Y-1089D01*
X1153805Y-1922D01*
X1152565Y-2547D01*
X1149465D01*
G01X1162175D02*
Y9953D01*
X1166050D01*
X1167290Y9328D01*
X1168065Y8495D01*
X1168375Y6828D01*
X1168065Y5161D01*
X1167135Y4120D01*
X1166050Y3495D01*
X1162175D01*
G01X1166050D02*
X1168375Y-2547D01*
G01X1175815Y9953D02*
X1179535D01*
G01X1177675D02*
Y-2547D01*
G01X1175815D02*
X1179535D01*
G01X1186975Y9953D02*
Y-2547D01*
X1193175D01*
G01X1199375Y9953D02*
Y-2547D01*
X1205575D01*
G01X1227275D02*
Y9953D01*
G01X1242465Y-2547D02*
Y5786D01*
G01Y4328D02*
X1241845Y5161D01*
X1240915Y5578D01*
X1239830Y5786D01*
X1238745Y5370D01*
X1237815Y4536D01*
X1237195Y3286D01*
X1236885Y1620D01*
X1237195Y-47D01*
X1237815Y-1297D01*
X1238745Y-2130D01*
X1239830Y-2547D01*
X1240915Y-2339D01*
X1241845Y-1714D01*
X1242465Y-881D01*
G01X1248820Y-6297D02*
X1249750Y-6714D01*
X1250990Y-6297D01*
X1251765Y-5464D01*
X1252385Y-4422D01*
X1253315Y-1089D01*
X1255330Y5786D01*
G01X1250370D02*
X1253315Y-1089D01*
G01X1262150Y3078D02*
X1267110D01*
X1266645Y4536D01*
X1265870Y5370D01*
X1264785Y5786D01*
X1263700Y5578D01*
X1262770Y4953D01*
X1262150Y3495D01*
X1261840Y2244D01*
Y995D01*
X1262150Y-255D01*
X1262925Y-1506D01*
X1263855Y-2339D01*
X1264940Y-2547D01*
X1266025Y-2130D01*
X1267110Y-881D01*
G01X1274705Y-2547D02*
Y5786D01*
G01Y4120D02*
X1275480Y4953D01*
X1276255Y5578D01*
X1277340Y5786D01*
X1278115Y5578D01*
X1279045Y4953D01*
G01X1300745Y-2547D02*
Y8078D01*
X1301055Y9119D01*
X1301675Y9745D01*
X1302605Y9953D01*
X1303535Y9536D01*
X1304000Y8495D01*
G01X1302140Y4953D02*
X1299040D01*
G01X1314075Y-2547D02*
X1313145Y-2339D01*
X1312215Y-1506D01*
X1311595Y-47D01*
X1311285Y1620D01*
X1311595Y3286D01*
X1312215Y4745D01*
X1313145Y5578D01*
X1314075Y5786D01*
X1315005Y5578D01*
X1315935Y4745D01*
X1316555Y3286D01*
X1316710Y1620D01*
X1316555Y-47D01*
X1315935Y-1506D01*
X1315005Y-2339D01*
X1314075Y-2547D01*
G01X1324305D02*
Y5786D01*
G01Y4120D02*
X1325080Y4953D01*
X1325855Y5578D01*
X1326940Y5786D01*
X1327715Y5578D01*
X1328645Y4953D01*
G01X1354375Y-2547D02*
X1348175D01*
Y9953D01*
X1354375D01*
G01X1351895Y3911D02*
X1348175D01*
G01X1360575Y9953D02*
Y-2547D01*
X1366775D01*
G01X1372975Y9953D02*
Y-2547D01*
X1379175D01*
G01X1386615Y9953D02*
X1390335D01*
G01X1388475D02*
Y-2547D01*
G01X1386615D02*
X1390335D01*
G01X1397775D02*
Y9953D01*
X1401495D01*
X1402735Y9328D01*
X1403665Y7870D01*
X1403975Y6203D01*
X1403665Y4536D01*
X1402890Y3286D01*
X1401495Y2661D01*
X1397775D01*
G01X1410020Y-881D02*
X1411260Y-1922D01*
X1412655Y-2547D01*
X1413895D01*
X1415135Y-1922D01*
X1416065Y-881D01*
X1416530Y578D01*
X1416220Y2036D01*
X1415445Y3286D01*
X1414050Y4120D01*
X1412190Y4536D01*
X1411105Y5370D01*
X1410640Y6828D01*
X1410950Y8286D01*
X1411725Y9328D01*
X1412810Y9953D01*
X1413895D01*
X1414980Y9536D01*
X1415910Y8495D01*
G01X1428775Y-2547D02*
X1422575D01*
Y9953D01*
X1428775D01*
G01X1426295Y3911D02*
X1422575D01*
G01X1453265Y9953D02*
Y-2547D01*
G01Y-672D02*
X1452645Y-1714D01*
X1451715Y-2339D01*
X1450630Y-2547D01*
X1449390Y-2130D01*
X1448460Y-1089D01*
X1447840Y161D01*
X1447685Y1620D01*
X1447840Y3078D01*
X1448460Y4328D01*
X1449390Y5370D01*
X1450630Y5786D01*
X1451715Y5578D01*
X1452490Y5161D01*
X1453265Y4328D01*
G01X1460705Y-2547D02*
Y5786D01*
G01Y4120D02*
X1461480Y4953D01*
X1462255Y5578D01*
X1463340Y5786D01*
X1464115Y5578D01*
X1465045Y4953D01*
G01X1475275Y5786D02*
Y-2547D01*
G01Y9119D02*
X1474965Y9328D01*
Y9745D01*
X1475275Y9953D01*
X1475585Y9745D01*
Y9328D01*
X1475275Y9119D01*
G01X1487675Y-2547D02*
Y9953D01*
G01X1500075Y-2547D02*
Y9953D01*
G01X1527665D02*
Y-2547D01*
G01Y-672D02*
X1527045Y-1714D01*
X1526115Y-2339D01*
X1525030Y-2547D01*
X1523790Y-2130D01*
X1522860Y-1089D01*
X1522240Y161D01*
X1522085Y1620D01*
X1522240Y3078D01*
X1522860Y4328D01*
X1523790Y5370D01*
X1525030Y5786D01*
X1526115Y5578D01*
X1526890Y5161D01*
X1527665Y4328D01*
G01X1537275Y5786D02*
Y-2547D01*
G01Y9119D02*
X1536965Y9328D01*
Y9745D01*
X1537275Y9953D01*
X1537585Y9745D01*
Y9328D01*
X1537275Y9119D01*
G01X1547505Y-2547D02*
Y5786D01*
G01Y4120D02*
X1548280Y4953D01*
X1549055Y5578D01*
X1550140Y5786D01*
X1550915Y5578D01*
X1551845Y4953D01*
G01X1559750Y3078D02*
X1564710D01*
X1564245Y4536D01*
X1563470Y5370D01*
X1562385Y5786D01*
X1561300Y5578D01*
X1560370Y4953D01*
X1559750Y3495D01*
X1559440Y2244D01*
Y995D01*
X1559750Y-255D01*
X1560525Y-1506D01*
X1561455Y-2339D01*
X1562540Y-2547D01*
X1563625Y-2130D01*
X1564710Y-881D01*
G01X1576955Y4745D02*
X1575870Y5578D01*
X1574940Y5786D01*
X1573700Y5370D01*
X1572770Y4536D01*
X1572150Y3078D01*
X1571995Y1620D01*
X1572150Y161D01*
X1572770Y-1089D01*
X1573700Y-2130D01*
X1574940Y-2547D01*
X1576025Y-2130D01*
X1576955Y-1297D01*
G01X1586875Y9953D02*
Y-2547D01*
G01X1584705Y5786D02*
X1589045D01*
G01X1599275D02*
Y-2547D01*
G01Y9119D02*
X1598965Y9328D01*
Y9745D01*
X1599275Y9953D01*
X1599585Y9745D01*
Y9328D01*
X1599275Y9119D01*
G01X1611675Y-2547D02*
X1610745Y-2339D01*
X1609815Y-1506D01*
X1609195Y-47D01*
X1608885Y1620D01*
X1609195Y3286D01*
X1609815Y4745D01*
X1610745Y5578D01*
X1611675Y5786D01*
X1612605Y5578D01*
X1613535Y4745D01*
X1614155Y3286D01*
X1614310Y1620D01*
X1614155Y-47D01*
X1613535Y-1506D01*
X1612605Y-2339D01*
X1611675Y-2547D01*
G01X1621440D02*
Y5786D01*
G01Y3703D02*
X1622060Y4745D01*
X1622990Y5578D01*
X1624230Y5786D01*
X1625315Y5578D01*
X1626245Y4745D01*
X1626710Y3286D01*
Y-2547D01*
G01X974625Y27453D02*
Y670653D01*
X1458225D01*
Y27453D01*
X974625D01*
G01Y111753D02*
X1458225D01*
G01X974625Y83653D02*
X1458225D01*
G01X974625Y55553D02*
X1458225D01*
G01X974625Y167953D02*
X1458225D01*
G01X974625Y139853D02*
X1458225D01*
G01X974625Y224153D02*
X1458225D01*
G01X974625Y196053D02*
X1458225D01*
G01X974625Y280353D02*
X1458225D01*
G01X974625Y252253D02*
X1458225D01*
G01X974625Y336553D02*
X1458225D01*
G01X974625Y308453D02*
X1458225D01*
G01X974625Y420853D02*
X1458225D01*
G01X974625Y392753D02*
X1458225D01*
G01X974625Y364653D02*
X1458225D01*
G01X974625Y477053D02*
X1458225D01*
G01X974625Y448953D02*
X1458225D01*
G01X974625Y533253D02*
X1458225D01*
G01X974625Y505153D02*
X1458225D01*
G01X985630Y598803D02*
Y611303D01*
X991520D01*
G01X989350Y605261D02*
X985630D01*
G01X999115Y611303D02*
X1002835D01*
G01X1000975D02*
Y598803D01*
G01X999115D02*
X1002835D01*
G01X1014305Y605053D02*
X1017405D01*
Y601303D01*
X1016475Y600053D01*
X1015390Y599220D01*
X1013840Y598803D01*
X1012290Y599220D01*
X1011205Y600053D01*
X1010275Y601303D01*
X1009655Y602761D01*
X1009345Y604428D01*
Y605886D01*
X1009655Y607136D01*
X1010275Y608595D01*
X1011205Y609845D01*
X1012135Y610678D01*
X1013375Y611303D01*
X1014460D01*
X1015700Y610886D01*
X1016630Y610053D01*
G01X1022365Y611303D02*
Y602345D01*
X1022985Y600469D01*
X1024225Y599220D01*
X1025775Y598803D01*
X1027325Y599220D01*
X1028565Y600469D01*
X1029185Y602345D01*
Y611303D01*
G01X1035075Y598803D02*
Y611303D01*
X1038950D01*
X1040190Y610678D01*
X1040965Y609845D01*
X1041275Y608178D01*
X1040965Y606511D01*
X1040035Y605470D01*
X1038950Y604845D01*
X1035075D01*
G01X1038950D02*
X1041275Y598803D01*
G01X1053675D02*
X1047475D01*
Y611303D01*
X1053675D01*
G01X1051195Y605261D02*
X1047475D01*
G01X974625Y589453D02*
X1458225D01*
G01X974625Y561353D02*
X1458225D01*
G01X974625Y645653D02*
X1458225D01*
G01X974625Y617553D02*
X1458225D01*
G01X1064525D02*
Y27453D01*
G01X1058015Y651903D02*
Y664403D01*
X1061115D01*
X1062355Y663778D01*
X1063285Y662945D01*
X1064060Y661695D01*
X1064680Y660236D01*
X1064835Y658153D01*
X1064680Y656070D01*
X1064060Y654611D01*
X1063285Y653361D01*
X1062355Y652528D01*
X1061115Y651903D01*
X1058015D01*
G01X1070725D02*
Y664403D01*
X1074600D01*
X1075840Y663778D01*
X1076615Y662945D01*
X1076925Y661278D01*
X1076615Y659611D01*
X1075685Y658570D01*
X1074600Y657945D01*
X1070725D01*
G01X1074600D02*
X1076925Y651903D01*
G01X1084365Y664403D02*
X1088085D01*
G01X1086225D02*
Y651903D01*
G01X1084365D02*
X1088085D01*
G01X1095525Y664403D02*
Y651903D01*
X1101725D01*
G01X1107925Y664403D02*
Y651903D01*
X1114125D01*
G01X1139235Y663361D02*
X1138305Y663986D01*
X1137220Y664403D01*
X1135980D01*
X1134585Y663778D01*
X1133500Y662736D01*
X1132725Y661486D01*
X1132105Y659403D01*
X1131950Y657528D01*
X1132260Y655653D01*
X1132725Y654403D01*
X1133655Y653153D01*
X1134740Y652320D01*
X1135825Y651903D01*
X1136910D01*
X1137995Y652320D01*
X1138925Y652944D01*
X1139700Y653778D01*
G01X1144970Y651903D02*
Y664403D01*
G01X1151480D02*
Y651903D01*
G01Y658153D02*
X1144970D01*
G01X1156750Y651903D02*
X1160625Y664403D01*
X1164500Y651903D01*
G01X1163105Y656278D02*
X1158145D01*
G01X1169925Y651903D02*
Y664403D01*
X1173800D01*
X1175040Y663778D01*
X1175815Y662945D01*
X1176125Y661278D01*
X1175815Y659611D01*
X1174885Y658570D01*
X1173800Y657945D01*
X1169925D01*
G01X1173800D02*
X1176125Y651903D01*
G01X1185425Y664403D02*
Y651903D01*
G01X1181860Y664403D02*
X1188990D01*
G01X1197825Y651486D02*
X1197515Y651695D01*
Y652111D01*
X1197825Y652320D01*
X1198135Y652111D01*
Y651695D01*
X1197825Y651486D01*
G01Y657111D02*
X1197515Y657320D01*
Y657736D01*
X1197825Y657945D01*
X1198135Y657736D01*
Y657320D01*
X1197825Y657111D01*
G01X1222625Y664403D02*
Y651903D01*
G01X1219060Y664403D02*
X1226190D01*
G01X1235025Y651903D02*
X1233785Y652111D01*
X1232700Y652944D01*
X1231770Y654195D01*
X1231150Y655653D01*
X1230840Y657320D01*
Y658986D01*
X1231150Y660653D01*
X1231770Y662111D01*
X1232700Y663361D01*
X1233785Y664195D01*
X1235025Y664403D01*
X1236265Y664195D01*
X1237350Y663361D01*
X1238280Y662111D01*
X1238900Y660653D01*
X1239210Y658986D01*
Y657320D01*
X1238900Y655653D01*
X1238280Y654195D01*
X1237350Y652944D01*
X1236265Y652111D01*
X1235025Y651903D01*
G01X1244325D02*
Y664403D01*
X1248045D01*
X1249285Y663778D01*
X1250215Y662320D01*
X1250525Y660653D01*
X1250215Y658986D01*
X1249440Y657736D01*
X1248045Y657111D01*
X1244325D01*
G01X1272225Y664403D02*
Y651903D01*
G01X1270055Y660236D02*
X1274395D01*
G01X1284625Y651903D02*
X1283695Y652111D01*
X1282765Y652944D01*
X1282145Y654403D01*
X1281835Y656070D01*
X1282145Y657736D01*
X1282765Y659195D01*
X1283695Y660028D01*
X1284625Y660236D01*
X1285555Y660028D01*
X1286485Y659195D01*
X1287105Y657736D01*
X1287260Y656070D01*
X1287105Y654403D01*
X1286485Y652944D01*
X1285555Y652111D01*
X1284625Y651903D01*
G01X1310665Y658570D02*
X1311285Y659195D01*
X1311750Y660236D01*
X1312060Y661695D01*
X1311750Y662945D01*
X1311130Y663778D01*
X1310045Y664403D01*
X1305860D01*
Y651903D01*
X1310975D01*
X1312060Y652736D01*
X1312680Y653986D01*
X1312990Y655445D01*
X1312680Y656903D01*
X1311750Y658153D01*
X1310665Y658570D01*
X1305860D01*
G01X1321825Y651903D02*
X1320585Y652111D01*
X1319500Y652944D01*
X1318570Y654195D01*
X1317950Y655653D01*
X1317640Y657320D01*
Y658986D01*
X1317950Y660653D01*
X1318570Y662111D01*
X1319500Y663361D01*
X1320585Y664195D01*
X1321825Y664403D01*
X1323065Y664195D01*
X1324150Y663361D01*
X1325080Y662111D01*
X1325700Y660653D01*
X1326010Y658986D01*
Y657320D01*
X1325700Y655653D01*
X1325080Y654195D01*
X1324150Y652944D01*
X1323065Y652111D01*
X1321825Y651903D01*
G01X1334225Y664403D02*
Y651903D01*
G01X1330660Y664403D02*
X1337790D01*
G01X1346625D02*
Y651903D01*
G01X1343060Y664403D02*
X1350190D01*
G01X1359025Y651903D02*
X1357785Y652111D01*
X1356700Y652944D01*
X1355770Y654195D01*
X1355150Y655653D01*
X1354840Y657320D01*
Y658986D01*
X1355150Y660653D01*
X1355770Y662111D01*
X1356700Y663361D01*
X1357785Y664195D01*
X1359025Y664403D01*
X1360265Y664195D01*
X1361350Y663361D01*
X1362280Y662111D01*
X1362900Y660653D01*
X1363210Y658986D01*
Y657320D01*
X1362900Y655653D01*
X1362280Y654195D01*
X1361350Y652944D01*
X1360265Y652111D01*
X1359025Y651903D01*
G01X1367395D02*
Y664403D01*
X1371425Y653986D01*
X1375455Y664403D01*
Y651903D01*
G01X1134275Y35253D02*
Y47753D01*
X1132415Y45253D01*
G01Y35253D02*
X1136135D01*
G01X1146675D02*
Y47753D01*
X1144815Y45253D01*
G01Y35253D02*
X1148535D01*
G01X1156440Y36711D02*
X1157525Y35670D01*
X1158765Y35253D01*
X1160005Y35670D01*
X1161090Y36919D01*
X1161865Y38795D01*
X1162175Y40670D01*
Y42961D01*
X1161865Y44836D01*
X1161090Y46503D01*
X1160160Y47336D01*
X1159075Y47753D01*
X1157835Y47336D01*
X1156905Y46503D01*
X1156285Y45253D01*
X1155975Y43586D01*
X1156285Y42128D01*
X1157060Y40670D01*
X1157990Y39836D01*
X1159075Y39628D01*
X1160315Y40044D01*
X1161245Y41086D01*
X1162175Y42961D01*
G01X1171475Y34836D02*
X1171165Y35045D01*
Y35461D01*
X1171475Y35670D01*
X1171785Y35461D01*
Y35045D01*
X1171475Y34836D01*
G01X1183875Y47753D02*
X1182635Y47336D01*
X1181705Y46295D01*
X1181085Y45045D01*
X1180620Y43378D01*
X1180465Y41503D01*
X1180620Y39628D01*
X1181085Y37961D01*
X1181705Y36711D01*
X1182635Y35670D01*
X1183875Y35253D01*
X1185115Y35670D01*
X1186045Y36711D01*
X1186665Y37961D01*
X1187130Y39628D01*
X1187285Y41503D01*
X1187130Y43378D01*
X1186665Y45045D01*
X1186045Y46295D01*
X1185115Y47336D01*
X1183875Y47753D01*
G01X1134275Y231953D02*
Y244453D01*
X1132415Y241953D01*
G01Y231953D02*
X1136135D01*
G01X1143265Y234453D02*
X1144195Y232994D01*
X1145435Y232161D01*
X1146830Y231953D01*
X1148070Y232161D01*
X1149310Y233203D01*
X1150085Y234453D01*
X1150240Y235703D01*
X1149930Y237161D01*
X1148845Y238203D01*
X1147760Y238620D01*
X1146365D01*
G01X1147760D02*
X1148690Y239245D01*
X1149465Y240286D01*
X1149775Y241536D01*
X1149465Y242786D01*
X1148690Y243828D01*
X1147295Y244453D01*
X1145900Y244245D01*
X1144505Y243411D01*
G01X1159075Y231953D02*
X1160160Y232161D01*
X1161400Y232786D01*
X1162175Y233828D01*
X1162485Y235286D01*
X1162175Y236744D01*
X1161245Y237995D01*
X1159850Y238620D01*
X1158300D01*
X1157370Y239036D01*
X1156595Y240078D01*
X1156285Y241536D01*
X1156750Y242995D01*
X1157835Y244036D01*
X1159075Y244453D01*
X1160315Y244036D01*
X1161400Y242995D01*
X1161865Y241536D01*
X1161555Y240078D01*
X1160780Y239036D01*
X1159850Y238620D01*
X1158300D01*
X1156905Y237995D01*
X1155975Y236744D01*
X1155665Y235286D01*
X1155975Y233828D01*
X1156750Y232786D01*
X1157990Y232161D01*
X1159075Y231953D01*
G01X1171475Y231536D02*
X1171165Y231745D01*
Y232161D01*
X1171475Y232370D01*
X1171785Y232161D01*
Y231745D01*
X1171475Y231536D01*
G01X1183875Y244453D02*
X1182635Y244036D01*
X1181705Y242995D01*
X1181085Y241745D01*
X1180620Y240078D01*
X1180465Y238203D01*
X1180620Y236328D01*
X1181085Y234661D01*
X1181705Y233411D01*
X1182635Y232370D01*
X1183875Y231953D01*
X1185115Y232370D01*
X1186045Y233411D01*
X1186665Y234661D01*
X1187130Y236328D01*
X1187285Y238203D01*
X1187130Y240078D01*
X1186665Y241745D01*
X1186045Y242995D01*
X1185115Y244036D01*
X1183875Y244453D01*
G01X1134275Y203853D02*
Y216353D01*
X1132415Y213853D01*
G01Y203853D02*
X1136135D01*
G01X1148535D02*
Y216353D01*
X1142800Y207395D01*
X1150550D01*
G01X1156130Y209061D02*
X1157215Y210520D01*
X1158145Y211353D01*
X1159385Y211770D01*
X1160470Y211353D01*
X1161245Y210520D01*
X1161865Y209270D01*
X1162020Y207811D01*
X1161865Y206561D01*
X1161245Y205311D01*
X1160315Y204270D01*
X1159230Y203853D01*
X1157990Y204270D01*
X1156905Y205519D01*
X1156285Y207395D01*
X1156130Y209478D01*
X1156440Y212186D01*
X1156905Y213645D01*
X1157680Y215103D01*
X1158765Y216145D01*
X1159850Y216353D01*
X1160935Y215936D01*
X1161710Y214895D01*
G01X1171475Y203436D02*
X1171165Y203645D01*
Y204061D01*
X1171475Y204270D01*
X1171785Y204061D01*
Y203645D01*
X1171475Y203436D01*
G01X1183875Y216353D02*
X1182635Y215936D01*
X1181705Y214895D01*
X1181085Y213645D01*
X1180620Y211978D01*
X1180465Y210103D01*
X1180620Y208228D01*
X1181085Y206561D01*
X1181705Y205311D01*
X1182635Y204270D01*
X1183875Y203853D01*
X1185115Y204270D01*
X1186045Y205311D01*
X1186665Y206561D01*
X1187130Y208228D01*
X1187285Y210103D01*
X1187130Y211978D01*
X1186665Y213645D01*
X1186045Y214895D01*
X1185115Y215936D01*
X1183875Y216353D01*
G01X1131330Y326670D02*
X1132260Y327919D01*
X1133345Y328545D01*
X1134585Y328753D01*
X1136135Y328336D01*
X1137220Y327295D01*
X1137530Y326045D01*
X1137375Y324794D01*
X1136755Y323753D01*
X1133655Y321670D01*
X1132260Y320211D01*
X1131330Y318128D01*
X1131020Y316253D01*
X1137530D01*
G01X1144040Y317711D02*
X1145125Y316670D01*
X1146365Y316253D01*
X1147605Y316670D01*
X1148690Y317919D01*
X1149465Y319795D01*
X1149775Y321670D01*
Y323961D01*
X1149465Y325836D01*
X1148690Y327503D01*
X1147760Y328336D01*
X1146675Y328753D01*
X1145435Y328336D01*
X1144505Y327503D01*
X1143885Y326253D01*
X1143575Y324586D01*
X1143885Y323128D01*
X1144660Y321670D01*
X1145590Y320836D01*
X1146675Y320628D01*
X1147915Y321044D01*
X1148845Y322086D01*
X1149775Y323961D01*
G01X1159075Y315836D02*
X1158765Y316045D01*
Y316461D01*
X1159075Y316670D01*
X1159385Y316461D01*
Y316045D01*
X1159075Y315836D01*
G01X1171475Y316253D02*
Y328753D01*
X1169615Y326253D01*
G01Y316253D02*
X1173335D01*
G01X1180465Y318753D02*
X1181395Y317294D01*
X1182635Y316461D01*
X1184030Y316253D01*
X1185270Y316461D01*
X1186510Y317503D01*
X1187285Y318753D01*
X1187440Y320003D01*
X1187130Y321461D01*
X1186045Y322503D01*
X1184960Y322920D01*
X1183565D01*
G01X1184960D02*
X1185890Y323545D01*
X1186665Y324586D01*
X1186975Y325836D01*
X1186665Y327086D01*
X1185890Y328128D01*
X1184495Y328753D01*
X1183100Y328545D01*
X1181705Y327711D01*
G01X1134275Y400553D02*
Y413053D01*
X1132415Y410553D01*
G01Y400553D02*
X1136135D01*
G01X1148535D02*
Y413053D01*
X1142800Y404095D01*
X1150550D01*
G01X1159075Y400136D02*
X1158765Y400345D01*
Y400761D01*
X1159075Y400970D01*
X1159385Y400761D01*
Y400345D01*
X1159075Y400136D01*
G01X1168065Y402428D02*
X1168995Y401386D01*
X1170080Y400761D01*
X1171475Y400553D01*
X1172870Y400970D01*
X1173955Y401803D01*
X1174730Y403261D01*
X1174885Y404928D01*
X1174575Y406595D01*
X1173800Y407636D01*
X1172715Y408470D01*
X1171630Y408678D01*
X1170545Y408470D01*
X1169150Y407636D01*
X1169615Y413053D01*
X1173800D01*
G01X1180930Y405761D02*
X1182015Y407220D01*
X1182945Y408053D01*
X1184185Y408470D01*
X1185270Y408053D01*
X1186045Y407220D01*
X1186665Y405970D01*
X1186820Y404511D01*
X1186665Y403261D01*
X1186045Y402011D01*
X1185115Y400970D01*
X1184030Y400553D01*
X1182790Y400970D01*
X1181705Y402219D01*
X1181085Y404095D01*
X1180930Y406178D01*
X1181240Y408886D01*
X1181705Y410345D01*
X1182480Y411803D01*
X1183565Y412845D01*
X1184650Y413053D01*
X1185735Y412636D01*
X1186510Y411595D01*
G01X1134275Y428653D02*
Y441153D01*
X1132415Y438653D01*
G01Y428653D02*
X1136135D01*
G01X1148535D02*
Y441153D01*
X1142800Y432195D01*
X1150550D01*
G01X1159075Y428236D02*
X1158765Y428445D01*
Y428861D01*
X1159075Y429070D01*
X1159385Y428861D01*
Y428445D01*
X1159075Y428236D01*
G01X1171475Y428653D02*
Y441153D01*
X1169615Y438653D01*
G01Y428653D02*
X1173335D01*
G01X1183565D02*
X1183875Y431361D01*
X1184340Y433653D01*
X1184960Y435736D01*
X1185735Y438028D01*
X1186975Y441153D01*
X1180775D01*
G01X1088550Y626903D02*
X1092425Y639403D01*
X1096300Y626903D01*
G01X1094905Y631278D02*
X1089945D01*
G01X1101725Y639403D02*
Y626903D01*
X1107925D01*
G01X1114125Y639403D02*
Y626903D01*
X1120325D01*
G01X1138615Y639403D02*
Y630445D01*
X1139235Y628569D01*
X1140475Y627320D01*
X1142025Y626903D01*
X1143575Y627320D01*
X1144815Y628569D01*
X1145435Y630445D01*
Y639403D01*
G01X1150860Y626903D02*
Y639403D01*
X1157990Y626903D01*
Y639403D01*
G01X1164965D02*
X1168685D01*
G01X1166825D02*
Y626903D01*
G01X1164965D02*
X1168685D01*
G01X1179225Y639403D02*
Y626903D01*
G01X1175660Y639403D02*
X1182790D01*
G01X1188370Y628569D02*
X1189610Y627528D01*
X1191005Y626903D01*
X1192245D01*
X1193485Y627528D01*
X1194415Y628569D01*
X1194880Y630028D01*
X1194570Y631486D01*
X1193795Y632736D01*
X1192400Y633570D01*
X1190540Y633986D01*
X1189455Y634820D01*
X1188990Y636278D01*
X1189300Y637736D01*
X1190075Y638778D01*
X1191160Y639403D01*
X1192245D01*
X1193330Y638986D01*
X1194260Y637945D01*
G01X1212550Y626903D02*
X1216425Y639403D01*
X1220300Y626903D01*
G01X1218905Y631278D02*
X1213945D01*
G01X1225725Y626903D02*
Y639403D01*
X1229600D01*
X1230840Y638778D01*
X1231615Y637945D01*
X1231925Y636278D01*
X1231615Y634611D01*
X1230685Y633570D01*
X1229600Y632945D01*
X1225725D01*
G01X1229600D02*
X1231925Y626903D01*
G01X1244325D02*
X1238125D01*
Y639403D01*
X1244325D01*
G01X1241845Y633361D02*
X1238125D01*
G01X1264165Y639403D02*
X1267885D01*
G01X1266025D02*
Y626903D01*
G01X1264165D02*
X1267885D01*
G01X1274860D02*
Y639403D01*
X1281990Y626903D01*
Y639403D01*
G01X1299195Y626903D02*
Y639403D01*
X1303225Y628986D01*
X1307255Y639403D01*
Y626903D01*
G01X1313765Y639403D02*
X1317485D01*
G01X1315625D02*
Y626903D01*
G01X1313765D02*
X1317485D01*
G01X1324925Y639403D02*
Y626903D01*
X1331125D01*
G01X1337170Y628569D02*
X1338410Y627528D01*
X1339805Y626903D01*
X1341045D01*
X1342285Y627528D01*
X1343215Y628569D01*
X1343680Y630028D01*
X1343370Y631486D01*
X1342595Y632736D01*
X1341200Y633570D01*
X1339340Y633986D01*
X1338255Y634820D01*
X1337790Y636278D01*
X1338100Y637736D01*
X1338875Y638778D01*
X1339960Y639403D01*
X1341045D01*
X1342130Y638986D01*
X1343060Y637945D01*
G01X1143132Y-369355D02*
X1141385Y-369938D01*
X1140075Y-371397D01*
X1139202Y-373146D01*
X1138547Y-375480D01*
X1138329Y-378105D01*
X1138547Y-380730D01*
X1139202Y-383064D01*
X1140075Y-384814D01*
X1141385Y-386272D01*
X1143132Y-386855D01*
X1144878Y-386272D01*
X1146189Y-384814D01*
X1147062Y-383064D01*
X1147717Y-380730D01*
X1147935Y-378105D01*
X1147717Y-375480D01*
X1147062Y-373146D01*
X1146189Y-371397D01*
X1144878Y-369938D01*
X1143132Y-369355D01*
G01X1156484Y-379564D02*
X1158012Y-377522D01*
X1159322Y-376355D01*
X1161069Y-375772D01*
X1162597Y-376355D01*
X1163689Y-377522D01*
X1164562Y-379272D01*
X1164780Y-381313D01*
X1164562Y-383064D01*
X1163689Y-384814D01*
X1162378Y-386272D01*
X1160850Y-386855D01*
X1159104Y-386272D01*
X1157575Y-384522D01*
X1156702Y-381897D01*
X1156484Y-378980D01*
X1156920Y-375189D01*
X1157575Y-373146D01*
X1158667Y-371105D01*
X1160195Y-369647D01*
X1161724Y-369355D01*
X1163252Y-369938D01*
X1164344Y-371397D01*
G01X1174202Y-387438D02*
X1182062Y-369355D01*
G01X1191484Y-372272D02*
X1192794Y-370522D01*
X1194322Y-369647D01*
X1196069Y-369355D01*
X1198252Y-369938D01*
X1199780Y-371397D01*
X1200217Y-373146D01*
X1199999Y-374897D01*
X1199125Y-376355D01*
X1194759Y-379272D01*
X1192794Y-381313D01*
X1191484Y-384231D01*
X1191047Y-386855D01*
X1200217D01*
G01X1213132D02*
Y-369355D01*
X1210512Y-372855D01*
G01Y-386855D02*
X1215752D01*
G01X1226702Y-387438D02*
X1234562Y-369355D01*
G01X1243984Y-372272D02*
X1245294Y-370522D01*
X1246822Y-369647D01*
X1248569Y-369355D01*
X1250752Y-369938D01*
X1252280Y-371397D01*
X1252717Y-373146D01*
X1252499Y-374897D01*
X1251625Y-376355D01*
X1247259Y-379272D01*
X1245294Y-381313D01*
X1243984Y-384231D01*
X1243547Y-386855D01*
X1252717D01*
G01X1265632Y-369355D02*
X1263885Y-369938D01*
X1262575Y-371397D01*
X1261702Y-373146D01*
X1261047Y-375480D01*
X1260829Y-378105D01*
X1261047Y-380730D01*
X1261702Y-383064D01*
X1262575Y-384814D01*
X1263885Y-386272D01*
X1265632Y-386855D01*
X1267378Y-386272D01*
X1268689Y-384814D01*
X1269562Y-383064D01*
X1270217Y-380730D01*
X1270435Y-378105D01*
X1270217Y-375480D01*
X1269562Y-373146D01*
X1268689Y-371397D01*
X1267378Y-369938D01*
X1265632Y-369355D01*
G01X1283132Y-386855D02*
Y-369355D01*
X1280512Y-372855D01*
G01Y-386855D02*
X1285752D01*
G01X1300195D02*
X1300632Y-383064D01*
X1301287Y-379855D01*
X1302160Y-376938D01*
X1303252Y-373730D01*
X1304999Y-369355D01*
X1296265D01*
G01X1190829Y-341855D02*
Y-324355D01*
X1195195D01*
X1196942Y-325230D01*
X1198252Y-326397D01*
X1199344Y-328146D01*
X1200217Y-330189D01*
X1200435Y-333105D01*
X1200217Y-336022D01*
X1199344Y-338064D01*
X1198252Y-339814D01*
X1196942Y-340980D01*
X1195195Y-341855D01*
X1190829D01*
G01X1217062D02*
Y-330189D01*
G01Y-332230D02*
X1216189Y-331064D01*
X1214878Y-330480D01*
X1213350Y-330189D01*
X1211822Y-330772D01*
X1210512Y-331938D01*
X1209638Y-333688D01*
X1209202Y-336022D01*
X1209638Y-338355D01*
X1210512Y-340105D01*
X1211822Y-341272D01*
X1213350Y-341855D01*
X1214878Y-341563D01*
X1216189Y-340689D01*
X1217062Y-339522D01*
G01X1230632Y-324355D02*
Y-341855D01*
G01X1227575Y-330189D02*
X1233689D01*
G01X1244857Y-333980D02*
X1251844D01*
X1251189Y-331938D01*
X1250097Y-330772D01*
X1248569Y-330189D01*
X1247040Y-330480D01*
X1245730Y-331355D01*
X1244857Y-333397D01*
X1244420Y-335147D01*
Y-336897D01*
X1244857Y-338647D01*
X1245949Y-340397D01*
X1247259Y-341563D01*
X1248787Y-341855D01*
X1250315Y-341272D01*
X1251844Y-339522D01*
G01X1137840Y92911D02*
X1138925Y91870D01*
X1140165Y91453D01*
X1141405Y91870D01*
X1142490Y93119D01*
X1143265Y94995D01*
X1143575Y96870D01*
Y99161D01*
X1143265Y101036D01*
X1142490Y102703D01*
X1141560Y103536D01*
X1140475Y103953D01*
X1139235Y103536D01*
X1138305Y102703D01*
X1137685Y101453D01*
X1137375Y99786D01*
X1137685Y98328D01*
X1138460Y96870D01*
X1139390Y96036D01*
X1140475Y95828D01*
X1141715Y96244D01*
X1142645Y97286D01*
X1143575Y99161D01*
G01X1154735Y91453D02*
Y103953D01*
X1149000Y94995D01*
X1156750D01*
G01X1165275Y91036D02*
X1164965Y91245D01*
Y91661D01*
X1165275Y91870D01*
X1165585Y91661D01*
Y91245D01*
X1165275Y91036D01*
G01X1177675Y103953D02*
X1176435Y103536D01*
X1175505Y102495D01*
X1174885Y101245D01*
X1174420Y99578D01*
X1174265Y97703D01*
X1174420Y95828D01*
X1174885Y94161D01*
X1175505Y92911D01*
X1176435Y91870D01*
X1177675Y91453D01*
X1178915Y91870D01*
X1179845Y92911D01*
X1180465Y94161D01*
X1180930Y95828D01*
X1181085Y97703D01*
X1180930Y99578D01*
X1180465Y101245D01*
X1179845Y102495D01*
X1178915Y103536D01*
X1177675Y103953D01*
G01X1137840Y64811D02*
X1138925Y63770D01*
X1140165Y63353D01*
X1141405Y63770D01*
X1142490Y65019D01*
X1143265Y66895D01*
X1143575Y68770D01*
Y71061D01*
X1143265Y72936D01*
X1142490Y74603D01*
X1141560Y75436D01*
X1140475Y75853D01*
X1139235Y75436D01*
X1138305Y74603D01*
X1137685Y73353D01*
X1137375Y71686D01*
X1137685Y70228D01*
X1138460Y68770D01*
X1139390Y67936D01*
X1140475Y67728D01*
X1141715Y68144D01*
X1142645Y69186D01*
X1143575Y71061D01*
G01X1152565Y63353D02*
X1152875Y66061D01*
X1153340Y68353D01*
X1153960Y70436D01*
X1154735Y72728D01*
X1155975Y75853D01*
X1149775D01*
G01X1165275Y62936D02*
X1164965Y63145D01*
Y63561D01*
X1165275Y63770D01*
X1165585Y63561D01*
Y63145D01*
X1165275Y62936D01*
G01X1177675Y75853D02*
X1176435Y75436D01*
X1175505Y74395D01*
X1174885Y73145D01*
X1174420Y71478D01*
X1174265Y69603D01*
X1174420Y67728D01*
X1174885Y66061D01*
X1175505Y64811D01*
X1176435Y63770D01*
X1177675Y63353D01*
X1178915Y63770D01*
X1179845Y64811D01*
X1180465Y66061D01*
X1180930Y67728D01*
X1181085Y69603D01*
X1180930Y71478D01*
X1180465Y73145D01*
X1179845Y74395D01*
X1178915Y75436D01*
X1177675Y75853D01*
G01X1142335Y175753D02*
Y188253D01*
X1136600Y179295D01*
X1144350D01*
G01X1149930Y186170D02*
X1150860Y187419D01*
X1151945Y188045D01*
X1153185Y188253D01*
X1154735Y187836D01*
X1155820Y186795D01*
X1156130Y185545D01*
X1155975Y184294D01*
X1155355Y183253D01*
X1152255Y181170D01*
X1150860Y179711D01*
X1149930Y177628D01*
X1149620Y175753D01*
X1156130D01*
G01X1165275Y175336D02*
X1164965Y175545D01*
Y175961D01*
X1165275Y176170D01*
X1165585Y175961D01*
Y175545D01*
X1165275Y175336D01*
G01X1177675Y188253D02*
X1176435Y187836D01*
X1175505Y186795D01*
X1174885Y185545D01*
X1174420Y183878D01*
X1174265Y182003D01*
X1174420Y180128D01*
X1174885Y178461D01*
X1175505Y177211D01*
X1176435Y176170D01*
X1177675Y175753D01*
X1178915Y176170D01*
X1179845Y177211D01*
X1180465Y178461D01*
X1180930Y180128D01*
X1181085Y182003D01*
X1180930Y183878D01*
X1180465Y185545D01*
X1179845Y186795D01*
X1178915Y187836D01*
X1177675Y188253D01*
G01X1140475Y147653D02*
X1141560Y147861D01*
X1142800Y148486D01*
X1143575Y149528D01*
X1143885Y150986D01*
X1143575Y152444D01*
X1142645Y153695D01*
X1141250Y154320D01*
X1139700D01*
X1138770Y154736D01*
X1137995Y155778D01*
X1137685Y157236D01*
X1138150Y158695D01*
X1139235Y159736D01*
X1140475Y160153D01*
X1141715Y159736D01*
X1142800Y158695D01*
X1143265Y157236D01*
X1142955Y155778D01*
X1142180Y154736D01*
X1141250Y154320D01*
X1139700D01*
X1138305Y153695D01*
X1137375Y152444D01*
X1137065Y150986D01*
X1137375Y149528D01*
X1138150Y148486D01*
X1139390Y147861D01*
X1140475Y147653D01*
G01X1149930Y152861D02*
X1151015Y154320D01*
X1151945Y155153D01*
X1153185Y155570D01*
X1154270Y155153D01*
X1155045Y154320D01*
X1155665Y153070D01*
X1155820Y151611D01*
X1155665Y150361D01*
X1155045Y149111D01*
X1154115Y148070D01*
X1153030Y147653D01*
X1151790Y148070D01*
X1150705Y149319D01*
X1150085Y151195D01*
X1149930Y153278D01*
X1150240Y155986D01*
X1150705Y157445D01*
X1151480Y158903D01*
X1152565Y159945D01*
X1153650Y160153D01*
X1154735Y159736D01*
X1155510Y158695D01*
G01X1165275Y147236D02*
X1164965Y147445D01*
Y147861D01*
X1165275Y148070D01*
X1165585Y147861D01*
Y147445D01*
X1165275Y147236D01*
G01X1177675Y160153D02*
X1176435Y159736D01*
X1175505Y158695D01*
X1174885Y157445D01*
X1174420Y155778D01*
X1174265Y153903D01*
X1174420Y152028D01*
X1174885Y150361D01*
X1175505Y149111D01*
X1176435Y148070D01*
X1177675Y147653D01*
X1178915Y148070D01*
X1179845Y149111D01*
X1180465Y150361D01*
X1180930Y152028D01*
X1181085Y153903D01*
X1180930Y155778D01*
X1180465Y157445D01*
X1179845Y158695D01*
X1178915Y159736D01*
X1177675Y160153D01*
G01X1140475Y119553D02*
X1141560Y119761D01*
X1142800Y120386D01*
X1143575Y121428D01*
X1143885Y122886D01*
X1143575Y124344D01*
X1142645Y125595D01*
X1141250Y126220D01*
X1139700D01*
X1138770Y126636D01*
X1137995Y127678D01*
X1137685Y129136D01*
X1138150Y130595D01*
X1139235Y131636D01*
X1140475Y132053D01*
X1141715Y131636D01*
X1142800Y130595D01*
X1143265Y129136D01*
X1142955Y127678D01*
X1142180Y126636D01*
X1141250Y126220D01*
X1139700D01*
X1138305Y125595D01*
X1137375Y124344D01*
X1137065Y122886D01*
X1137375Y121428D01*
X1138150Y120386D01*
X1139390Y119761D01*
X1140475Y119553D01*
G01X1152565D02*
X1152875Y122261D01*
X1153340Y124553D01*
X1153960Y126636D01*
X1154735Y128928D01*
X1155975Y132053D01*
X1149775D01*
G01X1165275Y119136D02*
X1164965Y119345D01*
Y119761D01*
X1165275Y119970D01*
X1165585Y119761D01*
Y119345D01*
X1165275Y119136D01*
G01X1177675Y132053D02*
X1176435Y131636D01*
X1175505Y130595D01*
X1174885Y129345D01*
X1174420Y127678D01*
X1174265Y125803D01*
X1174420Y123928D01*
X1174885Y122261D01*
X1175505Y121011D01*
X1176435Y119970D01*
X1177675Y119553D01*
X1178915Y119970D01*
X1179845Y121011D01*
X1180465Y122261D01*
X1180930Y123928D01*
X1181085Y125803D01*
X1180930Y127678D01*
X1180465Y129345D01*
X1179845Y130595D01*
X1178915Y131636D01*
X1177675Y132053D01*
G01X1137530Y293361D02*
X1138615Y294820D01*
X1139545Y295653D01*
X1140785Y296070D01*
X1141870Y295653D01*
X1142645Y294820D01*
X1143265Y293570D01*
X1143420Y292111D01*
X1143265Y290861D01*
X1142645Y289611D01*
X1141715Y288570D01*
X1140630Y288153D01*
X1139390Y288570D01*
X1138305Y289819D01*
X1137685Y291695D01*
X1137530Y293778D01*
X1137840Y296486D01*
X1138305Y297945D01*
X1139080Y299403D01*
X1140165Y300445D01*
X1141250Y300653D01*
X1142335Y300236D01*
X1143110Y299195D01*
G01X1149930Y298570D02*
X1150860Y299819D01*
X1151945Y300445D01*
X1153185Y300653D01*
X1154735Y300236D01*
X1155820Y299195D01*
X1156130Y297945D01*
X1155975Y296694D01*
X1155355Y295653D01*
X1152255Y293570D01*
X1150860Y292111D01*
X1149930Y290028D01*
X1149620Y288153D01*
X1156130D01*
G01X1165275Y287736D02*
X1164965Y287945D01*
Y288361D01*
X1165275Y288570D01*
X1165585Y288361D01*
Y287945D01*
X1165275Y287736D01*
G01X1177675Y300653D02*
X1176435Y300236D01*
X1175505Y299195D01*
X1174885Y297945D01*
X1174420Y296278D01*
X1174265Y294403D01*
X1174420Y292528D01*
X1174885Y290861D01*
X1175505Y289611D01*
X1176435Y288570D01*
X1177675Y288153D01*
X1178915Y288570D01*
X1179845Y289611D01*
X1180465Y290861D01*
X1180930Y292528D01*
X1181085Y294403D01*
X1180930Y296278D01*
X1180465Y297945D01*
X1179845Y299195D01*
X1178915Y300236D01*
X1177675Y300653D01*
G01X1140475Y260053D02*
X1141560Y260261D01*
X1142800Y260886D01*
X1143575Y261928D01*
X1143885Y263386D01*
X1143575Y264844D01*
X1142645Y266095D01*
X1141250Y266720D01*
X1139700D01*
X1138770Y267136D01*
X1137995Y268178D01*
X1137685Y269636D01*
X1138150Y271095D01*
X1139235Y272136D01*
X1140475Y272553D01*
X1141715Y272136D01*
X1142800Y271095D01*
X1143265Y269636D01*
X1142955Y268178D01*
X1142180Y267136D01*
X1141250Y266720D01*
X1139700D01*
X1138305Y266095D01*
X1137375Y264844D01*
X1137065Y263386D01*
X1137375Y261928D01*
X1138150Y260886D01*
X1139390Y260261D01*
X1140475Y260053D01*
G01X1149465Y262553D02*
X1150395Y261094D01*
X1151635Y260261D01*
X1153030Y260053D01*
X1154270Y260261D01*
X1155510Y261303D01*
X1156285Y262553D01*
X1156440Y263803D01*
X1156130Y265261D01*
X1155045Y266303D01*
X1153960Y266720D01*
X1152565D01*
G01X1153960D02*
X1154890Y267345D01*
X1155665Y268386D01*
X1155975Y269636D01*
X1155665Y270886D01*
X1154890Y271928D01*
X1153495Y272553D01*
X1152100Y272345D01*
X1150705Y271511D01*
G01X1165275Y259636D02*
X1164965Y259845D01*
Y260261D01*
X1165275Y260470D01*
X1165585Y260261D01*
Y259845D01*
X1165275Y259636D01*
G01X1177675Y272553D02*
X1176435Y272136D01*
X1175505Y271095D01*
X1174885Y269845D01*
X1174420Y268178D01*
X1174265Y266303D01*
X1174420Y264428D01*
X1174885Y262761D01*
X1175505Y261511D01*
X1176435Y260470D01*
X1177675Y260053D01*
X1178915Y260470D01*
X1179845Y261511D01*
X1180465Y262761D01*
X1180930Y264428D01*
X1181085Y266303D01*
X1180930Y268178D01*
X1180465Y269845D01*
X1179845Y271095D01*
X1178915Y272136D01*
X1177675Y272553D01*
G01X1137530Y354770D02*
X1138460Y356019D01*
X1139545Y356645D01*
X1140785Y356853D01*
X1142335Y356436D01*
X1143420Y355395D01*
X1143730Y354145D01*
X1143575Y352894D01*
X1142955Y351853D01*
X1139855Y349770D01*
X1138460Y348311D01*
X1137530Y346228D01*
X1137220Y344353D01*
X1143730D01*
G01X1152875Y356853D02*
X1151635Y356436D01*
X1150705Y355395D01*
X1150085Y354145D01*
X1149620Y352478D01*
X1149465Y350603D01*
X1149620Y348728D01*
X1150085Y347061D01*
X1150705Y345811D01*
X1151635Y344770D01*
X1152875Y344353D01*
X1154115Y344770D01*
X1155045Y345811D01*
X1155665Y347061D01*
X1156130Y348728D01*
X1156285Y350603D01*
X1156130Y352478D01*
X1155665Y354145D01*
X1155045Y355395D01*
X1154115Y356436D01*
X1152875Y356853D01*
G01X1165275Y343936D02*
X1164965Y344145D01*
Y344561D01*
X1165275Y344770D01*
X1165585Y344561D01*
Y344145D01*
X1165275Y343936D01*
G01X1177675Y356853D02*
X1176435Y356436D01*
X1175505Y355395D01*
X1174885Y354145D01*
X1174420Y352478D01*
X1174265Y350603D01*
X1174420Y348728D01*
X1174885Y347061D01*
X1175505Y345811D01*
X1176435Y344770D01*
X1177675Y344353D01*
X1178915Y344770D01*
X1179845Y345811D01*
X1180465Y347061D01*
X1180930Y348728D01*
X1181085Y350603D01*
X1180930Y352478D01*
X1180465Y354145D01*
X1179845Y355395D01*
X1178915Y356436D01*
X1177675Y356853D01*
G01X1140475Y372453D02*
Y384953D01*
X1138615Y382453D01*
G01Y372453D02*
X1142335D01*
G01X1149930Y377661D02*
X1151015Y379120D01*
X1151945Y379953D01*
X1153185Y380370D01*
X1154270Y379953D01*
X1155045Y379120D01*
X1155665Y377870D01*
X1155820Y376411D01*
X1155665Y375161D01*
X1155045Y373911D01*
X1154115Y372870D01*
X1153030Y372453D01*
X1151790Y372870D01*
X1150705Y374119D01*
X1150085Y375995D01*
X1149930Y378078D01*
X1150240Y380786D01*
X1150705Y382245D01*
X1151480Y383703D01*
X1152565Y384745D01*
X1153650Y384953D01*
X1154735Y384536D01*
X1155510Y383495D01*
G01X1165275Y372036D02*
X1164965Y372245D01*
Y372661D01*
X1165275Y372870D01*
X1165585Y372661D01*
Y372245D01*
X1165275Y372036D01*
G01X1177675Y384953D02*
X1176435Y384536D01*
X1175505Y383495D01*
X1174885Y382245D01*
X1174420Y380578D01*
X1174265Y378703D01*
X1174420Y376828D01*
X1174885Y375161D01*
X1175505Y373911D01*
X1176435Y372870D01*
X1177675Y372453D01*
X1178915Y372870D01*
X1179845Y373911D01*
X1180465Y375161D01*
X1180930Y376828D01*
X1181085Y378703D01*
X1180930Y380578D01*
X1180465Y382245D01*
X1179845Y383495D01*
X1178915Y384536D01*
X1177675Y384953D01*
G01X1140475Y484853D02*
Y497353D01*
X1138615Y494853D01*
G01Y484853D02*
X1142335D01*
G01X1149930Y495270D02*
X1150860Y496519D01*
X1151945Y497145D01*
X1153185Y497353D01*
X1154735Y496936D01*
X1155820Y495895D01*
X1156130Y494645D01*
X1155975Y493394D01*
X1155355Y492353D01*
X1152255Y490270D01*
X1150860Y488811D01*
X1149930Y486728D01*
X1149620Y484853D01*
X1156130D01*
G01X1165275Y484436D02*
X1164965Y484645D01*
Y485061D01*
X1165275Y485270D01*
X1165585Y485061D01*
Y484645D01*
X1165275Y484436D01*
G01X1177675Y497353D02*
X1176435Y496936D01*
X1175505Y495895D01*
X1174885Y494645D01*
X1174420Y492978D01*
X1174265Y491103D01*
X1174420Y489228D01*
X1174885Y487561D01*
X1175505Y486311D01*
X1176435Y485270D01*
X1177675Y484853D01*
X1178915Y485270D01*
X1179845Y486311D01*
X1180465Y487561D01*
X1180930Y489228D01*
X1181085Y491103D01*
X1180930Y492978D01*
X1180465Y494645D01*
X1179845Y495895D01*
X1178915Y496936D01*
X1177675Y497353D01*
G01X1140475Y456753D02*
Y469253D01*
X1138615Y466753D01*
G01Y456753D02*
X1142335D01*
G01X1154735D02*
Y469253D01*
X1149000Y460295D01*
X1156750D01*
G01X1165275Y456336D02*
X1164965Y456545D01*
Y456961D01*
X1165275Y457170D01*
X1165585Y456961D01*
Y456545D01*
X1165275Y456336D01*
G01X1177675Y469253D02*
X1176435Y468836D01*
X1175505Y467795D01*
X1174885Y466545D01*
X1174420Y464878D01*
X1174265Y463003D01*
X1174420Y461128D01*
X1174885Y459461D01*
X1175505Y458211D01*
X1176435Y457170D01*
X1177675Y456753D01*
X1178915Y457170D01*
X1179845Y458211D01*
X1180465Y459461D01*
X1180930Y461128D01*
X1181085Y463003D01*
X1180930Y464878D01*
X1180465Y466545D01*
X1179845Y467795D01*
X1178915Y468836D01*
X1177675Y469253D01*
G01X1140475Y541053D02*
Y553553D01*
X1138615Y551053D01*
G01Y541053D02*
X1142335D01*
G01X1152875Y553553D02*
X1151635Y553136D01*
X1150705Y552095D01*
X1150085Y550845D01*
X1149620Y549178D01*
X1149465Y547303D01*
X1149620Y545428D01*
X1150085Y543761D01*
X1150705Y542511D01*
X1151635Y541470D01*
X1152875Y541053D01*
X1154115Y541470D01*
X1155045Y542511D01*
X1155665Y543761D01*
X1156130Y545428D01*
X1156285Y547303D01*
X1156130Y549178D01*
X1155665Y550845D01*
X1155045Y552095D01*
X1154115Y553136D01*
X1152875Y553553D01*
G01X1165275Y540636D02*
X1164965Y540845D01*
Y541261D01*
X1165275Y541470D01*
X1165585Y541261D01*
Y540845D01*
X1165275Y540636D01*
G01X1177675Y553553D02*
X1176435Y553136D01*
X1175505Y552095D01*
X1174885Y550845D01*
X1174420Y549178D01*
X1174265Y547303D01*
X1174420Y545428D01*
X1174885Y543761D01*
X1175505Y542511D01*
X1176435Y541470D01*
X1177675Y541053D01*
X1178915Y541470D01*
X1179845Y542511D01*
X1180465Y543761D01*
X1180930Y545428D01*
X1181085Y547303D01*
X1180930Y549178D01*
X1180465Y550845D01*
X1179845Y552095D01*
X1178915Y553136D01*
X1177675Y553553D01*
G01X1140475Y512953D02*
Y525453D01*
X1138615Y522953D01*
G01Y512953D02*
X1142335D01*
G01X1152875Y525453D02*
X1151635Y525036D01*
X1150705Y523995D01*
X1150085Y522745D01*
X1149620Y521078D01*
X1149465Y519203D01*
X1149620Y517328D01*
X1150085Y515661D01*
X1150705Y514411D01*
X1151635Y513370D01*
X1152875Y512953D01*
X1154115Y513370D01*
X1155045Y514411D01*
X1155665Y515661D01*
X1156130Y517328D01*
X1156285Y519203D01*
X1156130Y521078D01*
X1155665Y522745D01*
X1155045Y523995D01*
X1154115Y525036D01*
X1152875Y525453D01*
G01X1165275Y512536D02*
X1164965Y512745D01*
Y513161D01*
X1165275Y513370D01*
X1165585Y513161D01*
Y512745D01*
X1165275Y512536D01*
G01X1177675Y525453D02*
X1176435Y525036D01*
X1175505Y523995D01*
X1174885Y522745D01*
X1174420Y521078D01*
X1174265Y519203D01*
X1174420Y517328D01*
X1174885Y515661D01*
X1175505Y514411D01*
X1176435Y513370D01*
X1177675Y512953D01*
X1178915Y513370D01*
X1179845Y514411D01*
X1180465Y515661D01*
X1180930Y517328D01*
X1181085Y519203D01*
X1180930Y521078D01*
X1180465Y522745D01*
X1179845Y523995D01*
X1178915Y525036D01*
X1177675Y525453D01*
G01X1137220Y600469D02*
X1138460Y599428D01*
X1139855Y598803D01*
X1141095D01*
X1142335Y599428D01*
X1143265Y600469D01*
X1143730Y601928D01*
X1143420Y603386D01*
X1142645Y604636D01*
X1141250Y605470D01*
X1139390Y605886D01*
X1138305Y606720D01*
X1137840Y608178D01*
X1138150Y609636D01*
X1138925Y610678D01*
X1140010Y611303D01*
X1141095D01*
X1142180Y610886D01*
X1143110Y609845D01*
G01X1151015Y611303D02*
X1154735D01*
G01X1152875D02*
Y598803D01*
G01X1151015D02*
X1154735D01*
G01X1162330Y611303D02*
X1168220D01*
X1162330Y598803D01*
X1168220D01*
G01X1180775D02*
X1174575D01*
Y611303D01*
X1180775D01*
G01X1178295Y605261D02*
X1174575D01*
G01X1146675Y569153D02*
X1147760Y569361D01*
X1149000Y569986D01*
X1149775Y571028D01*
X1150085Y572486D01*
X1149775Y573944D01*
X1148845Y575195D01*
X1147450Y575820D01*
X1145900D01*
X1144970Y576236D01*
X1144195Y577278D01*
X1143885Y578736D01*
X1144350Y580195D01*
X1145435Y581236D01*
X1146675Y581653D01*
X1147915Y581236D01*
X1149000Y580195D01*
X1149465Y578736D01*
X1149155Y577278D01*
X1148380Y576236D01*
X1147450Y575820D01*
X1145900D01*
X1144505Y575195D01*
X1143575Y573944D01*
X1143265Y572486D01*
X1143575Y571028D01*
X1144350Y569986D01*
X1145590Y569361D01*
X1146675Y569153D01*
G01X1159075Y568736D02*
X1158765Y568945D01*
Y569361D01*
X1159075Y569570D01*
X1159385Y569361D01*
Y568945D01*
X1159075Y568736D01*
G01X1171475Y581653D02*
X1170235Y581236D01*
X1169305Y580195D01*
X1168685Y578945D01*
X1168220Y577278D01*
X1168065Y575403D01*
X1168220Y573528D01*
X1168685Y571861D01*
X1169305Y570611D01*
X1170235Y569570D01*
X1171475Y569153D01*
X1172715Y569570D01*
X1173645Y570611D01*
X1174265Y571861D01*
X1174730Y573528D01*
X1174885Y575403D01*
X1174730Y577278D01*
X1174265Y578945D01*
X1173645Y580195D01*
X1172715Y581236D01*
X1171475Y581653D01*
G01X1253625Y617553D02*
Y27453D01*
G01X1257810Y35253D02*
Y47753D01*
X1264940Y35253D01*
Y47753D01*
G01X1273775Y35253D02*
X1272535Y35461D01*
X1271450Y36294D01*
X1270520Y37545D01*
X1269900Y39003D01*
X1269590Y40670D01*
Y42336D01*
X1269900Y44003D01*
X1270520Y45461D01*
X1271450Y46711D01*
X1272535Y47545D01*
X1273775Y47753D01*
X1275015Y47545D01*
X1276100Y46711D01*
X1277030Y45461D01*
X1277650Y44003D01*
X1277960Y42336D01*
Y40670D01*
X1277650Y39003D01*
X1277030Y37545D01*
X1276100Y36294D01*
X1275015Y35461D01*
X1273775Y35253D01*
G01X1282610D02*
Y47753D01*
X1289740Y35253D01*
Y47753D01*
G01X1296560Y39420D02*
X1300590D01*
G01X1307875Y35253D02*
Y47753D01*
X1311595D01*
X1312835Y47128D01*
X1313765Y45670D01*
X1314075Y44003D01*
X1313765Y42336D01*
X1312990Y41086D01*
X1311595Y40461D01*
X1307875D01*
G01X1320275Y47753D02*
Y35253D01*
X1326475D01*
G01X1331900D02*
X1335775Y47753D01*
X1339650Y35253D01*
G01X1338255Y39628D02*
X1333295D01*
G01X1348175Y47753D02*
Y35253D01*
G01X1344610Y47753D02*
X1351740D01*
G01X1363675Y35253D02*
X1357475D01*
Y47753D01*
X1363675D01*
G01X1361195Y41711D02*
X1357475D01*
G01X1369565Y35253D02*
Y47753D01*
X1372665D01*
X1373905Y47128D01*
X1374835Y46295D01*
X1375610Y45045D01*
X1376230Y43586D01*
X1376385Y41503D01*
X1376230Y39420D01*
X1375610Y37961D01*
X1374835Y36711D01*
X1373905Y35878D01*
X1372665Y35253D01*
X1369565D01*
G01X1257810Y91453D02*
Y103953D01*
X1264940Y91453D01*
Y103953D01*
G01X1273775Y91453D02*
X1272535Y91661D01*
X1271450Y92494D01*
X1270520Y93745D01*
X1269900Y95203D01*
X1269590Y96870D01*
Y98536D01*
X1269900Y100203D01*
X1270520Y101661D01*
X1271450Y102911D01*
X1272535Y103745D01*
X1273775Y103953D01*
X1275015Y103745D01*
X1276100Y102911D01*
X1277030Y101661D01*
X1277650Y100203D01*
X1277960Y98536D01*
Y96870D01*
X1277650Y95203D01*
X1277030Y93745D01*
X1276100Y92494D01*
X1275015Y91661D01*
X1273775Y91453D01*
G01X1282610D02*
Y103953D01*
X1289740Y91453D01*
Y103953D01*
G01X1296560Y95620D02*
X1300590D01*
G01X1307875Y91453D02*
Y103953D01*
X1311595D01*
X1312835Y103328D01*
X1313765Y101870D01*
X1314075Y100203D01*
X1313765Y98536D01*
X1312990Y97286D01*
X1311595Y96661D01*
X1307875D01*
G01X1320275Y103953D02*
Y91453D01*
X1326475D01*
G01X1331900D02*
X1335775Y103953D01*
X1339650Y91453D01*
G01X1338255Y95828D02*
X1333295D01*
G01X1348175Y103953D02*
Y91453D01*
G01X1344610Y103953D02*
X1351740D01*
G01X1363675Y91453D02*
X1357475D01*
Y103953D01*
X1363675D01*
G01X1361195Y97911D02*
X1357475D01*
G01X1369565Y91453D02*
Y103953D01*
X1372665D01*
X1373905Y103328D01*
X1374835Y102495D01*
X1375610Y101245D01*
X1376230Y99786D01*
X1376385Y97703D01*
X1376230Y95620D01*
X1375610Y94161D01*
X1374835Y92911D01*
X1373905Y92078D01*
X1372665Y91453D01*
X1369565D01*
G01X1257810Y63353D02*
Y75853D01*
X1264940Y63353D01*
Y75853D01*
G01X1273775Y63353D02*
X1272535Y63561D01*
X1271450Y64394D01*
X1270520Y65645D01*
X1269900Y67103D01*
X1269590Y68770D01*
Y70436D01*
X1269900Y72103D01*
X1270520Y73561D01*
X1271450Y74811D01*
X1272535Y75645D01*
X1273775Y75853D01*
X1275015Y75645D01*
X1276100Y74811D01*
X1277030Y73561D01*
X1277650Y72103D01*
X1277960Y70436D01*
Y68770D01*
X1277650Y67103D01*
X1277030Y65645D01*
X1276100Y64394D01*
X1275015Y63561D01*
X1273775Y63353D01*
G01X1282610D02*
Y75853D01*
X1289740Y63353D01*
Y75853D01*
G01X1296560Y67520D02*
X1300590D01*
G01X1307875Y63353D02*
Y75853D01*
X1311595D01*
X1312835Y75228D01*
X1313765Y73770D01*
X1314075Y72103D01*
X1313765Y70436D01*
X1312990Y69186D01*
X1311595Y68561D01*
X1307875D01*
G01X1320275Y75853D02*
Y63353D01*
X1326475D01*
G01X1331900D02*
X1335775Y75853D01*
X1339650Y63353D01*
G01X1338255Y67728D02*
X1333295D01*
G01X1348175Y75853D02*
Y63353D01*
G01X1344610Y75853D02*
X1351740D01*
G01X1363675Y63353D02*
X1357475D01*
Y75853D01*
X1363675D01*
G01X1361195Y69811D02*
X1357475D01*
G01X1369565Y63353D02*
Y75853D01*
X1372665D01*
X1373905Y75228D01*
X1374835Y74395D01*
X1375610Y73145D01*
X1376230Y71686D01*
X1376385Y69603D01*
X1376230Y67520D01*
X1375610Y66061D01*
X1374835Y64811D01*
X1373905Y63978D01*
X1372665Y63353D01*
X1369565D01*
G01X1257810Y175753D02*
Y188253D01*
X1264940Y175753D01*
Y188253D01*
G01X1273775Y175753D02*
X1272535Y175961D01*
X1271450Y176794D01*
X1270520Y178045D01*
X1269900Y179503D01*
X1269590Y181170D01*
Y182836D01*
X1269900Y184503D01*
X1270520Y185961D01*
X1271450Y187211D01*
X1272535Y188045D01*
X1273775Y188253D01*
X1275015Y188045D01*
X1276100Y187211D01*
X1277030Y185961D01*
X1277650Y184503D01*
X1277960Y182836D01*
Y181170D01*
X1277650Y179503D01*
X1277030Y178045D01*
X1276100Y176794D01*
X1275015Y175961D01*
X1273775Y175753D01*
G01X1282610D02*
Y188253D01*
X1289740Y175753D01*
Y188253D01*
G01X1296560Y179920D02*
X1300590D01*
G01X1307875Y175753D02*
Y188253D01*
X1311595D01*
X1312835Y187628D01*
X1313765Y186170D01*
X1314075Y184503D01*
X1313765Y182836D01*
X1312990Y181586D01*
X1311595Y180961D01*
X1307875D01*
G01X1320275Y188253D02*
Y175753D01*
X1326475D01*
G01X1331900D02*
X1335775Y188253D01*
X1339650Y175753D01*
G01X1338255Y180128D02*
X1333295D01*
G01X1348175Y188253D02*
Y175753D01*
G01X1344610Y188253D02*
X1351740D01*
G01X1363675Y175753D02*
X1357475D01*
Y188253D01*
X1363675D01*
G01X1361195Y182211D02*
X1357475D01*
G01X1369565Y175753D02*
Y188253D01*
X1372665D01*
X1373905Y187628D01*
X1374835Y186795D01*
X1375610Y185545D01*
X1376230Y184086D01*
X1376385Y182003D01*
X1376230Y179920D01*
X1375610Y178461D01*
X1374835Y177211D01*
X1373905Y176378D01*
X1372665Y175753D01*
X1369565D01*
G01X1257810Y147653D02*
Y160153D01*
X1264940Y147653D01*
Y160153D01*
G01X1273775Y147653D02*
X1272535Y147861D01*
X1271450Y148694D01*
X1270520Y149945D01*
X1269900Y151403D01*
X1269590Y153070D01*
Y154736D01*
X1269900Y156403D01*
X1270520Y157861D01*
X1271450Y159111D01*
X1272535Y159945D01*
X1273775Y160153D01*
X1275015Y159945D01*
X1276100Y159111D01*
X1277030Y157861D01*
X1277650Y156403D01*
X1277960Y154736D01*
Y153070D01*
X1277650Y151403D01*
X1277030Y149945D01*
X1276100Y148694D01*
X1275015Y147861D01*
X1273775Y147653D01*
G01X1282610D02*
Y160153D01*
X1289740Y147653D01*
Y160153D01*
G01X1296560Y151820D02*
X1300590D01*
G01X1307875Y147653D02*
Y160153D01*
X1311595D01*
X1312835Y159528D01*
X1313765Y158070D01*
X1314075Y156403D01*
X1313765Y154736D01*
X1312990Y153486D01*
X1311595Y152861D01*
X1307875D01*
G01X1320275Y160153D02*
Y147653D01*
X1326475D01*
G01X1331900D02*
X1335775Y160153D01*
X1339650Y147653D01*
G01X1338255Y152028D02*
X1333295D01*
G01X1348175Y160153D02*
Y147653D01*
G01X1344610Y160153D02*
X1351740D01*
G01X1363675Y147653D02*
X1357475D01*
Y160153D01*
X1363675D01*
G01X1361195Y154111D02*
X1357475D01*
G01X1369565Y147653D02*
Y160153D01*
X1372665D01*
X1373905Y159528D01*
X1374835Y158695D01*
X1375610Y157445D01*
X1376230Y155986D01*
X1376385Y153903D01*
X1376230Y151820D01*
X1375610Y150361D01*
X1374835Y149111D01*
X1373905Y148278D01*
X1372665Y147653D01*
X1369565D01*
G01X1257810Y119553D02*
Y132053D01*
X1264940Y119553D01*
Y132053D01*
G01X1273775Y119553D02*
X1272535Y119761D01*
X1271450Y120594D01*
X1270520Y121845D01*
X1269900Y123303D01*
X1269590Y124970D01*
Y126636D01*
X1269900Y128303D01*
X1270520Y129761D01*
X1271450Y131011D01*
X1272535Y131845D01*
X1273775Y132053D01*
X1275015Y131845D01*
X1276100Y131011D01*
X1277030Y129761D01*
X1277650Y128303D01*
X1277960Y126636D01*
Y124970D01*
X1277650Y123303D01*
X1277030Y121845D01*
X1276100Y120594D01*
X1275015Y119761D01*
X1273775Y119553D01*
G01X1282610D02*
Y132053D01*
X1289740Y119553D01*
Y132053D01*
G01X1296560Y123720D02*
X1300590D01*
G01X1307875Y119553D02*
Y132053D01*
X1311595D01*
X1312835Y131428D01*
X1313765Y129970D01*
X1314075Y128303D01*
X1313765Y126636D01*
X1312990Y125386D01*
X1311595Y124761D01*
X1307875D01*
G01X1320275Y132053D02*
Y119553D01*
X1326475D01*
G01X1331900D02*
X1335775Y132053D01*
X1339650Y119553D01*
G01X1338255Y123928D02*
X1333295D01*
G01X1348175Y132053D02*
Y119553D01*
G01X1344610Y132053D02*
X1351740D01*
G01X1363675Y119553D02*
X1357475D01*
Y132053D01*
X1363675D01*
G01X1361195Y126011D02*
X1357475D01*
G01X1369565Y119553D02*
Y132053D01*
X1372665D01*
X1373905Y131428D01*
X1374835Y130595D01*
X1375610Y129345D01*
X1376230Y127886D01*
X1376385Y125803D01*
X1376230Y123720D01*
X1375610Y122261D01*
X1374835Y121011D01*
X1373905Y120178D01*
X1372665Y119553D01*
X1369565D01*
G01X1283075Y231953D02*
Y244453D01*
X1286795D01*
X1288035Y243828D01*
X1288965Y242370D01*
X1289275Y240703D01*
X1288965Y239036D01*
X1288190Y237786D01*
X1286795Y237161D01*
X1283075D01*
G01X1295475Y244453D02*
Y231953D01*
X1301675D01*
G01X1307100D02*
X1310975Y244453D01*
X1314850Y231953D01*
G01X1313455Y236328D02*
X1308495D01*
G01X1323375Y244453D02*
Y231953D01*
G01X1319810Y244453D02*
X1326940D01*
G01X1338875Y231953D02*
X1332675D01*
Y244453D01*
X1338875D01*
G01X1336395Y238411D02*
X1332675D01*
G01X1344765Y231953D02*
Y244453D01*
X1347865D01*
X1349105Y243828D01*
X1350035Y242995D01*
X1350810Y241745D01*
X1351430Y240286D01*
X1351585Y238203D01*
X1351430Y236120D01*
X1350810Y234661D01*
X1350035Y233411D01*
X1349105Y232578D01*
X1347865Y231953D01*
X1344765D01*
G01X1283075Y203853D02*
Y216353D01*
X1286795D01*
X1288035Y215728D01*
X1288965Y214270D01*
X1289275Y212603D01*
X1288965Y210936D01*
X1288190Y209686D01*
X1286795Y209061D01*
X1283075D01*
G01X1295475Y216353D02*
Y203853D01*
X1301675D01*
G01X1307100D02*
X1310975Y216353D01*
X1314850Y203853D01*
G01X1313455Y208228D02*
X1308495D01*
G01X1323375Y216353D02*
Y203853D01*
G01X1319810Y216353D02*
X1326940D01*
G01X1338875Y203853D02*
X1332675D01*
Y216353D01*
X1338875D01*
G01X1336395Y210311D02*
X1332675D01*
G01X1344765Y203853D02*
Y216353D01*
X1347865D01*
X1349105Y215728D01*
X1350035Y214895D01*
X1350810Y213645D01*
X1351430Y212186D01*
X1351585Y210103D01*
X1351430Y208020D01*
X1350810Y206561D01*
X1350035Y205311D01*
X1349105Y204478D01*
X1347865Y203853D01*
X1344765D01*
G01X1283075Y288153D02*
Y300653D01*
X1286795D01*
X1288035Y300028D01*
X1288965Y298570D01*
X1289275Y296903D01*
X1288965Y295236D01*
X1288190Y293986D01*
X1286795Y293361D01*
X1283075D01*
G01X1295475Y300653D02*
Y288153D01*
X1301675D01*
G01X1307100D02*
X1310975Y300653D01*
X1314850Y288153D01*
G01X1313455Y292528D02*
X1308495D01*
G01X1323375Y300653D02*
Y288153D01*
G01X1319810Y300653D02*
X1326940D01*
G01X1338875Y288153D02*
X1332675D01*
Y300653D01*
X1338875D01*
G01X1336395Y294611D02*
X1332675D01*
G01X1344765Y288153D02*
Y300653D01*
X1347865D01*
X1349105Y300028D01*
X1350035Y299195D01*
X1350810Y297945D01*
X1351430Y296486D01*
X1351585Y294403D01*
X1351430Y292320D01*
X1350810Y290861D01*
X1350035Y289611D01*
X1349105Y288778D01*
X1347865Y288153D01*
X1344765D01*
G01X1283075Y260053D02*
Y272553D01*
X1286795D01*
X1288035Y271928D01*
X1288965Y270470D01*
X1289275Y268803D01*
X1288965Y267136D01*
X1288190Y265886D01*
X1286795Y265261D01*
X1283075D01*
G01X1295475Y272553D02*
Y260053D01*
X1301675D01*
G01X1307100D02*
X1310975Y272553D01*
X1314850Y260053D01*
G01X1313455Y264428D02*
X1308495D01*
G01X1323375Y272553D02*
Y260053D01*
G01X1319810Y272553D02*
X1326940D01*
G01X1338875Y260053D02*
X1332675D01*
Y272553D01*
X1338875D01*
G01X1336395Y266511D02*
X1332675D01*
G01X1344765Y260053D02*
Y272553D01*
X1347865D01*
X1349105Y271928D01*
X1350035Y271095D01*
X1350810Y269845D01*
X1351430Y268386D01*
X1351585Y266303D01*
X1351430Y264220D01*
X1350810Y262761D01*
X1350035Y261511D01*
X1349105Y260678D01*
X1347865Y260053D01*
X1344765D01*
G01X1283075Y344353D02*
Y356853D01*
X1286795D01*
X1288035Y356228D01*
X1288965Y354770D01*
X1289275Y353103D01*
X1288965Y351436D01*
X1288190Y350186D01*
X1286795Y349561D01*
X1283075D01*
G01X1295475Y356853D02*
Y344353D01*
X1301675D01*
G01X1307100D02*
X1310975Y356853D01*
X1314850Y344353D01*
G01X1313455Y348728D02*
X1308495D01*
G01X1323375Y356853D02*
Y344353D01*
G01X1319810Y356853D02*
X1326940D01*
G01X1338875Y344353D02*
X1332675D01*
Y356853D01*
X1338875D01*
G01X1336395Y350811D02*
X1332675D01*
G01X1344765Y344353D02*
Y356853D01*
X1347865D01*
X1349105Y356228D01*
X1350035Y355395D01*
X1350810Y354145D01*
X1351430Y352686D01*
X1351585Y350603D01*
X1351430Y348520D01*
X1350810Y347061D01*
X1350035Y345811D01*
X1349105Y344978D01*
X1347865Y344353D01*
X1344765D01*
G01X1283075Y316253D02*
Y328753D01*
X1286795D01*
X1288035Y328128D01*
X1288965Y326670D01*
X1289275Y325003D01*
X1288965Y323336D01*
X1288190Y322086D01*
X1286795Y321461D01*
X1283075D01*
G01X1295475Y328753D02*
Y316253D01*
X1301675D01*
G01X1307100D02*
X1310975Y328753D01*
X1314850Y316253D01*
G01X1313455Y320628D02*
X1308495D01*
G01X1323375Y328753D02*
Y316253D01*
G01X1319810Y328753D02*
X1326940D01*
G01X1338875Y316253D02*
X1332675D01*
Y328753D01*
X1338875D01*
G01X1336395Y322711D02*
X1332675D01*
G01X1344765Y316253D02*
Y328753D01*
X1347865D01*
X1349105Y328128D01*
X1350035Y327295D01*
X1350810Y326045D01*
X1351430Y324586D01*
X1351585Y322503D01*
X1351430Y320420D01*
X1350810Y318961D01*
X1350035Y317711D01*
X1349105Y316878D01*
X1347865Y316253D01*
X1344765D01*
G01X1283075Y400553D02*
Y413053D01*
X1286795D01*
X1288035Y412428D01*
X1288965Y410970D01*
X1289275Y409303D01*
X1288965Y407636D01*
X1288190Y406386D01*
X1286795Y405761D01*
X1283075D01*
G01X1295475Y413053D02*
Y400553D01*
X1301675D01*
G01X1307100D02*
X1310975Y413053D01*
X1314850Y400553D01*
G01X1313455Y404928D02*
X1308495D01*
G01X1323375Y413053D02*
Y400553D01*
G01X1319810Y413053D02*
X1326940D01*
G01X1338875Y400553D02*
X1332675D01*
Y413053D01*
X1338875D01*
G01X1336395Y407011D02*
X1332675D01*
G01X1344765Y400553D02*
Y413053D01*
X1347865D01*
X1349105Y412428D01*
X1350035Y411595D01*
X1350810Y410345D01*
X1351430Y408886D01*
X1351585Y406803D01*
X1351430Y404720D01*
X1350810Y403261D01*
X1350035Y402011D01*
X1349105Y401178D01*
X1347865Y400553D01*
X1344765D01*
G01X1283075Y372453D02*
Y384953D01*
X1286795D01*
X1288035Y384328D01*
X1288965Y382870D01*
X1289275Y381203D01*
X1288965Y379536D01*
X1288190Y378286D01*
X1286795Y377661D01*
X1283075D01*
G01X1295475Y384953D02*
Y372453D01*
X1301675D01*
G01X1307100D02*
X1310975Y384953D01*
X1314850Y372453D01*
G01X1313455Y376828D02*
X1308495D01*
G01X1323375Y384953D02*
Y372453D01*
G01X1319810Y384953D02*
X1326940D01*
G01X1338875Y372453D02*
X1332675D01*
Y384953D01*
X1338875D01*
G01X1336395Y378911D02*
X1332675D01*
G01X1344765Y372453D02*
Y384953D01*
X1347865D01*
X1349105Y384328D01*
X1350035Y383495D01*
X1350810Y382245D01*
X1351430Y380786D01*
X1351585Y378703D01*
X1351430Y376620D01*
X1350810Y375161D01*
X1350035Y373911D01*
X1349105Y373078D01*
X1347865Y372453D01*
X1344765D01*
G01X1283075Y484853D02*
Y497353D01*
X1286795D01*
X1288035Y496728D01*
X1288965Y495270D01*
X1289275Y493603D01*
X1288965Y491936D01*
X1288190Y490686D01*
X1286795Y490061D01*
X1283075D01*
G01X1295475Y497353D02*
Y484853D01*
X1301675D01*
G01X1307100D02*
X1310975Y497353D01*
X1314850Y484853D01*
G01X1313455Y489228D02*
X1308495D01*
G01X1323375Y497353D02*
Y484853D01*
G01X1319810Y497353D02*
X1326940D01*
G01X1338875Y484853D02*
X1332675D01*
Y497353D01*
X1338875D01*
G01X1336395Y491311D02*
X1332675D01*
G01X1344765Y484853D02*
Y497353D01*
X1347865D01*
X1349105Y496728D01*
X1350035Y495895D01*
X1350810Y494645D01*
X1351430Y493186D01*
X1351585Y491103D01*
X1351430Y489020D01*
X1350810Y487561D01*
X1350035Y486311D01*
X1349105Y485478D01*
X1347865Y484853D01*
X1344765D01*
G01X1283075Y456753D02*
Y469253D01*
X1286795D01*
X1288035Y468628D01*
X1288965Y467170D01*
X1289275Y465503D01*
X1288965Y463836D01*
X1288190Y462586D01*
X1286795Y461961D01*
X1283075D01*
G01X1295475Y469253D02*
Y456753D01*
X1301675D01*
G01X1307100D02*
X1310975Y469253D01*
X1314850Y456753D01*
G01X1313455Y461128D02*
X1308495D01*
G01X1323375Y469253D02*
Y456753D01*
G01X1319810Y469253D02*
X1326940D01*
G01X1338875Y456753D02*
X1332675D01*
Y469253D01*
X1338875D01*
G01X1336395Y463211D02*
X1332675D01*
G01X1344765Y456753D02*
Y469253D01*
X1347865D01*
X1349105Y468628D01*
X1350035Y467795D01*
X1350810Y466545D01*
X1351430Y465086D01*
X1351585Y463003D01*
X1351430Y460920D01*
X1350810Y459461D01*
X1350035Y458211D01*
X1349105Y457378D01*
X1347865Y456753D01*
X1344765D01*
G01X1283075Y428653D02*
Y441153D01*
X1286795D01*
X1288035Y440528D01*
X1288965Y439070D01*
X1289275Y437403D01*
X1288965Y435736D01*
X1288190Y434486D01*
X1286795Y433861D01*
X1283075D01*
G01X1295475Y441153D02*
Y428653D01*
X1301675D01*
G01X1307100D02*
X1310975Y441153D01*
X1314850Y428653D01*
G01X1313455Y433028D02*
X1308495D01*
G01X1323375Y441153D02*
Y428653D01*
G01X1319810Y441153D02*
X1326940D01*
G01X1338875Y428653D02*
X1332675D01*
Y441153D01*
X1338875D01*
G01X1336395Y435111D02*
X1332675D01*
G01X1344765Y428653D02*
Y441153D01*
X1347865D01*
X1349105Y440528D01*
X1350035Y439695D01*
X1350810Y438445D01*
X1351430Y436986D01*
X1351585Y434903D01*
X1351430Y432820D01*
X1350810Y431361D01*
X1350035Y430111D01*
X1349105Y429278D01*
X1347865Y428653D01*
X1344765D01*
G01X1283075Y541053D02*
Y553553D01*
X1286795D01*
X1288035Y552928D01*
X1288965Y551470D01*
X1289275Y549803D01*
X1288965Y548136D01*
X1288190Y546886D01*
X1286795Y546261D01*
X1283075D01*
G01X1295475Y553553D02*
Y541053D01*
X1301675D01*
G01X1307100D02*
X1310975Y553553D01*
X1314850Y541053D01*
G01X1313455Y545428D02*
X1308495D01*
G01X1323375Y553553D02*
Y541053D01*
G01X1319810Y553553D02*
X1326940D01*
G01X1338875Y541053D02*
X1332675D01*
Y553553D01*
X1338875D01*
G01X1336395Y547511D02*
X1332675D01*
G01X1344765Y541053D02*
Y553553D01*
X1347865D01*
X1349105Y552928D01*
X1350035Y552095D01*
X1350810Y550845D01*
X1351430Y549386D01*
X1351585Y547303D01*
X1351430Y545220D01*
X1350810Y543761D01*
X1350035Y542511D01*
X1349105Y541678D01*
X1347865Y541053D01*
X1344765D01*
G01X1283075Y512953D02*
Y525453D01*
X1286795D01*
X1288035Y524828D01*
X1288965Y523370D01*
X1289275Y521703D01*
X1288965Y520036D01*
X1288190Y518786D01*
X1286795Y518161D01*
X1283075D01*
G01X1295475Y525453D02*
Y512953D01*
X1301675D01*
G01X1307100D02*
X1310975Y525453D01*
X1314850Y512953D01*
G01X1313455Y517328D02*
X1308495D01*
G01X1323375Y525453D02*
Y512953D01*
G01X1319810Y525453D02*
X1326940D01*
G01X1338875Y512953D02*
X1332675D01*
Y525453D01*
X1338875D01*
G01X1336395Y519411D02*
X1332675D01*
G01X1344765Y512953D02*
Y525453D01*
X1347865D01*
X1349105Y524828D01*
X1350035Y523995D01*
X1350810Y522745D01*
X1351430Y521286D01*
X1351585Y519203D01*
X1351430Y517120D01*
X1350810Y515661D01*
X1350035Y514411D01*
X1349105Y513578D01*
X1347865Y512953D01*
X1344765D01*
G01X1283075Y598803D02*
Y611303D01*
X1286795D01*
X1288035Y610678D01*
X1288965Y609220D01*
X1289275Y607553D01*
X1288965Y605886D01*
X1288190Y604636D01*
X1286795Y604011D01*
X1283075D01*
G01X1295475Y611303D02*
Y598803D01*
X1301675D01*
G01X1307100D02*
X1310975Y611303D01*
X1314850Y598803D01*
G01X1313455Y603178D02*
X1308495D01*
G01X1323375Y611303D02*
Y598803D01*
G01X1319810Y611303D02*
X1326940D01*
G01X1338875Y598803D02*
X1332675D01*
Y611303D01*
X1338875D01*
G01X1336395Y605261D02*
X1332675D01*
G01X1344765Y598803D02*
Y611303D01*
X1347865D01*
X1349105Y610678D01*
X1350035Y609845D01*
X1350810Y608595D01*
X1351430Y607136D01*
X1351585Y605053D01*
X1351430Y602970D01*
X1350810Y601511D01*
X1350035Y600261D01*
X1349105Y599428D01*
X1347865Y598803D01*
X1344765D01*
G01X1283075Y569153D02*
Y581653D01*
X1286795D01*
X1288035Y581028D01*
X1288965Y579570D01*
X1289275Y577903D01*
X1288965Y576236D01*
X1288190Y574986D01*
X1286795Y574361D01*
X1283075D01*
G01X1295475Y581653D02*
Y569153D01*
X1301675D01*
G01X1307100D02*
X1310975Y581653D01*
X1314850Y569153D01*
G01X1313455Y573528D02*
X1308495D01*
G01X1323375Y581653D02*
Y569153D01*
G01X1319810Y581653D02*
X1326940D01*
G01X1338875Y569153D02*
X1332675D01*
Y581653D01*
X1338875D01*
G01X1336395Y575611D02*
X1332675D01*
G01X1344765Y569153D02*
Y581653D01*
X1347865D01*
X1349105Y581028D01*
X1350035Y580195D01*
X1350810Y578945D01*
X1351430Y577486D01*
X1351585Y575403D01*
X1351430Y573320D01*
X1350810Y571861D01*
X1350035Y570611D01*
X1349105Y569778D01*
X1347865Y569153D01*
X1344765D01*
G01X1421335Y35253D02*
Y47753D01*
X1415600Y38795D01*
X1423350D01*
G01X1380725Y617553D02*
Y27453D01*
G01X1419475Y91453D02*
Y103953D01*
X1417615Y101453D01*
G01Y91453D02*
X1421335D01*
G01X1419475Y63353D02*
Y75853D01*
X1417615Y73353D01*
G01Y63353D02*
X1421335D01*
G01X1416530Y186170D02*
X1417460Y187419D01*
X1418545Y188045D01*
X1419785Y188253D01*
X1421335Y187836D01*
X1422420Y186795D01*
X1422730Y185545D01*
X1422575Y184294D01*
X1421955Y183253D01*
X1418855Y181170D01*
X1417460Y179711D01*
X1416530Y177628D01*
X1416220Y175753D01*
X1422730D01*
G01X1416530Y152861D02*
X1417615Y154320D01*
X1418545Y155153D01*
X1419785Y155570D01*
X1420870Y155153D01*
X1421645Y154320D01*
X1422265Y153070D01*
X1422420Y151611D01*
X1422265Y150361D01*
X1421645Y149111D01*
X1420715Y148070D01*
X1419630Y147653D01*
X1418390Y148070D01*
X1417305Y149319D01*
X1416685Y151195D01*
X1416530Y153278D01*
X1416840Y155986D01*
X1417305Y157445D01*
X1418080Y158903D01*
X1419165Y159945D01*
X1420250Y160153D01*
X1421335Y159736D01*
X1422110Y158695D01*
G01X1416530Y129970D02*
X1417460Y131219D01*
X1418545Y131845D01*
X1419785Y132053D01*
X1421335Y131636D01*
X1422420Y130595D01*
X1422730Y129345D01*
X1422575Y128094D01*
X1421955Y127053D01*
X1418855Y124970D01*
X1417460Y123511D01*
X1416530Y121428D01*
X1416220Y119553D01*
X1422730D01*
G01X1416530Y242370D02*
X1417460Y243619D01*
X1418545Y244245D01*
X1419785Y244453D01*
X1421335Y244036D01*
X1422420Y242995D01*
X1422730Y241745D01*
X1422575Y240494D01*
X1421955Y239453D01*
X1418855Y237370D01*
X1417460Y235911D01*
X1416530Y233828D01*
X1416220Y231953D01*
X1422730D01*
G01X1416530Y214270D02*
X1417460Y215519D01*
X1418545Y216145D01*
X1419785Y216353D01*
X1421335Y215936D01*
X1422420Y214895D01*
X1422730Y213645D01*
X1422575Y212394D01*
X1421955Y211353D01*
X1418855Y209270D01*
X1417460Y207811D01*
X1416530Y205728D01*
X1416220Y203853D01*
X1422730D01*
G01X1416530Y298570D02*
X1417460Y299819D01*
X1418545Y300445D01*
X1419785Y300653D01*
X1421335Y300236D01*
X1422420Y299195D01*
X1422730Y297945D01*
X1422575Y296694D01*
X1421955Y295653D01*
X1418855Y293570D01*
X1417460Y292111D01*
X1416530Y290028D01*
X1416220Y288153D01*
X1422730D01*
G01X1416530Y270470D02*
X1417460Y271719D01*
X1418545Y272345D01*
X1419785Y272553D01*
X1421335Y272136D01*
X1422420Y271095D01*
X1422730Y269845D01*
X1422575Y268594D01*
X1421955Y267553D01*
X1418855Y265470D01*
X1417460Y264011D01*
X1416530Y261928D01*
X1416220Y260053D01*
X1422730D01*
G01X1413275Y344353D02*
Y356853D01*
X1411415Y354353D01*
G01Y344353D02*
X1415135D01*
G01X1423040Y345811D02*
X1424125Y344770D01*
X1425365Y344353D01*
X1426605Y344770D01*
X1427690Y346019D01*
X1428465Y347895D01*
X1428775Y349770D01*
Y352061D01*
X1428465Y353936D01*
X1427690Y355603D01*
X1426760Y356436D01*
X1425675Y356853D01*
X1424435Y356436D01*
X1423505Y355603D01*
X1422885Y354353D01*
X1422575Y352686D01*
X1422885Y351228D01*
X1423660Y349770D01*
X1424590Y348936D01*
X1425675Y348728D01*
X1426915Y349144D01*
X1427845Y350186D01*
X1428775Y352061D01*
G01X1413275Y316253D02*
Y328753D01*
X1411415Y326253D01*
G01Y316253D02*
X1415135D01*
G01X1422730Y326670D02*
X1423660Y327919D01*
X1424745Y328545D01*
X1425985Y328753D01*
X1427535Y328336D01*
X1428620Y327295D01*
X1428930Y326045D01*
X1428775Y324794D01*
X1428155Y323753D01*
X1425055Y321670D01*
X1423660Y320211D01*
X1422730Y318128D01*
X1422420Y316253D01*
X1428930D01*
G01X1409865Y403053D02*
X1410795Y401594D01*
X1412035Y400761D01*
X1413430Y400553D01*
X1414670Y400761D01*
X1415910Y401803D01*
X1416685Y403053D01*
X1416840Y404303D01*
X1416530Y405761D01*
X1415445Y406803D01*
X1414360Y407220D01*
X1412965D01*
G01X1414360D02*
X1415290Y407845D01*
X1416065Y408886D01*
X1416375Y410136D01*
X1416065Y411386D01*
X1415290Y412428D01*
X1413895Y413053D01*
X1412500Y412845D01*
X1411105Y412011D01*
G01X1422730Y405761D02*
X1423815Y407220D01*
X1424745Y408053D01*
X1425985Y408470D01*
X1427070Y408053D01*
X1427845Y407220D01*
X1428465Y405970D01*
X1428620Y404511D01*
X1428465Y403261D01*
X1427845Y402011D01*
X1426915Y400970D01*
X1425830Y400553D01*
X1424590Y400970D01*
X1423505Y402219D01*
X1422885Y404095D01*
X1422730Y406178D01*
X1423040Y408886D01*
X1423505Y410345D01*
X1424280Y411803D01*
X1425365Y412845D01*
X1426450Y413053D01*
X1427535Y412636D01*
X1428310Y411595D01*
G01X1407075Y372453D02*
X1408160Y372661D01*
X1409400Y373286D01*
X1410175Y374328D01*
X1410485Y375786D01*
X1410175Y377244D01*
X1409245Y378495D01*
X1407850Y379120D01*
X1406300D01*
X1405370Y379536D01*
X1404595Y380578D01*
X1404285Y382036D01*
X1404750Y383495D01*
X1405835Y384536D01*
X1407075Y384953D01*
X1408315Y384536D01*
X1409400Y383495D01*
X1409865Y382036D01*
X1409555Y380578D01*
X1408780Y379536D01*
X1407850Y379120D01*
X1406300D01*
X1404905Y378495D01*
X1403975Y377244D01*
X1403665Y375786D01*
X1403975Y374328D01*
X1404750Y373286D01*
X1405990Y372661D01*
X1407075Y372453D01*
G01X1416065Y374953D02*
X1416995Y373494D01*
X1418235Y372661D01*
X1419630Y372453D01*
X1420870Y372661D01*
X1422110Y373703D01*
X1422885Y374953D01*
X1423040Y376203D01*
X1422730Y377661D01*
X1421645Y378703D01*
X1420560Y379120D01*
X1419165D01*
G01X1420560D02*
X1421490Y379745D01*
X1422265Y380786D01*
X1422575Y382036D01*
X1422265Y383286D01*
X1421490Y384328D01*
X1420095Y384953D01*
X1418700Y384745D01*
X1417305Y383911D01*
G01X1431875Y384953D02*
X1430635Y384536D01*
X1429705Y383495D01*
X1429085Y382245D01*
X1428620Y380578D01*
X1428465Y378703D01*
X1428620Y376828D01*
X1429085Y375161D01*
X1429705Y373911D01*
X1430635Y372870D01*
X1431875Y372453D01*
X1433115Y372870D01*
X1434045Y373911D01*
X1434665Y375161D01*
X1435130Y376828D01*
X1435285Y378703D01*
X1435130Y380578D01*
X1434665Y382245D01*
X1434045Y383495D01*
X1433115Y384536D01*
X1431875Y384953D01*
G01X1410330Y490061D02*
X1411415Y491520D01*
X1412345Y492353D01*
X1413585Y492770D01*
X1414670Y492353D01*
X1415445Y491520D01*
X1416065Y490270D01*
X1416220Y488811D01*
X1416065Y487561D01*
X1415445Y486311D01*
X1414515Y485270D01*
X1413430Y484853D01*
X1412190Y485270D01*
X1411105Y486519D01*
X1410485Y488395D01*
X1410330Y490478D01*
X1410640Y493186D01*
X1411105Y494645D01*
X1411880Y496103D01*
X1412965Y497145D01*
X1414050Y497353D01*
X1415135Y496936D01*
X1415910Y495895D01*
G01X1425365Y484853D02*
X1425675Y487561D01*
X1426140Y489853D01*
X1426760Y491936D01*
X1427535Y494228D01*
X1428775Y497353D01*
X1422575D01*
G01X1410330Y467170D02*
X1411260Y468419D01*
X1412345Y469045D01*
X1413585Y469253D01*
X1415135Y468836D01*
X1416220Y467795D01*
X1416530Y466545D01*
X1416375Y465294D01*
X1415755Y464253D01*
X1412655Y462170D01*
X1411260Y460711D01*
X1410330Y458628D01*
X1410020Y456753D01*
X1416530D01*
G01X1422730Y461961D02*
X1423815Y463420D01*
X1424745Y464253D01*
X1425985Y464670D01*
X1427070Y464253D01*
X1427845Y463420D01*
X1428465Y462170D01*
X1428620Y460711D01*
X1428465Y459461D01*
X1427845Y458211D01*
X1426915Y457170D01*
X1425830Y456753D01*
X1424590Y457170D01*
X1423505Y458419D01*
X1422885Y460295D01*
X1422730Y462378D01*
X1423040Y465086D01*
X1423505Y466545D01*
X1424280Y468003D01*
X1425365Y469045D01*
X1426450Y469253D01*
X1427535Y468836D01*
X1428310Y467795D01*
G01X1408935Y428653D02*
Y441153D01*
X1403200Y432195D01*
X1410950D01*
G01X1419475Y428653D02*
Y441153D01*
X1417615Y438653D01*
G01Y428653D02*
X1421335D01*
G01X1431875D02*
X1432960Y428861D01*
X1434200Y429486D01*
X1434975Y430528D01*
X1435285Y431986D01*
X1434975Y433444D01*
X1434045Y434695D01*
X1432650Y435320D01*
X1431100D01*
X1430170Y435736D01*
X1429395Y436778D01*
X1429085Y438236D01*
X1429550Y439695D01*
X1430635Y440736D01*
X1431875Y441153D01*
X1433115Y440736D01*
X1434200Y439695D01*
X1434665Y438236D01*
X1434355Y436778D01*
X1433580Y435736D01*
X1432650Y435320D01*
X1431100D01*
X1429705Y434695D01*
X1428775Y433444D01*
X1428465Y431986D01*
X1428775Y430528D01*
X1429550Y429486D01*
X1430790Y428861D01*
X1431875Y428653D01*
G01X1400875Y541053D02*
Y553553D01*
X1399015Y551053D01*
G01Y541053D02*
X1402735D01*
G01X1409865Y543553D02*
X1410795Y542094D01*
X1412035Y541261D01*
X1413430Y541053D01*
X1414670Y541261D01*
X1415910Y542303D01*
X1416685Y543553D01*
X1416840Y544803D01*
X1416530Y546261D01*
X1415445Y547303D01*
X1414360Y547720D01*
X1412965D01*
G01X1414360D02*
X1415290Y548345D01*
X1416065Y549386D01*
X1416375Y550636D01*
X1416065Y551886D01*
X1415290Y552928D01*
X1413895Y553553D01*
X1412500Y553345D01*
X1411105Y552511D01*
G01X1422730Y546261D02*
X1423815Y547720D01*
X1424745Y548553D01*
X1425985Y548970D01*
X1427070Y548553D01*
X1427845Y547720D01*
X1428465Y546470D01*
X1428620Y545011D01*
X1428465Y543761D01*
X1427845Y542511D01*
X1426915Y541470D01*
X1425830Y541053D01*
X1424590Y541470D01*
X1423505Y542719D01*
X1422885Y544595D01*
X1422730Y546678D01*
X1423040Y549386D01*
X1423505Y550845D01*
X1424280Y552303D01*
X1425365Y553345D01*
X1426450Y553553D01*
X1427535Y553136D01*
X1428310Y552095D01*
G01X1438075Y541053D02*
X1439160Y541261D01*
X1440400Y541886D01*
X1441175Y542928D01*
X1441485Y544386D01*
X1441175Y545844D01*
X1440245Y547095D01*
X1438850Y547720D01*
X1437300D01*
X1436370Y548136D01*
X1435595Y549178D01*
X1435285Y550636D01*
X1435750Y552095D01*
X1436835Y553136D01*
X1438075Y553553D01*
X1439315Y553136D01*
X1440400Y552095D01*
X1440865Y550636D01*
X1440555Y549178D01*
X1439780Y548136D01*
X1438850Y547720D01*
X1437300D01*
X1435905Y547095D01*
X1434975Y545844D01*
X1434665Y544386D01*
X1434975Y542928D01*
X1435750Y541886D01*
X1436990Y541261D01*
X1438075Y541053D01*
G01X1416840Y514411D02*
X1417925Y513370D01*
X1419165Y512953D01*
X1420405Y513370D01*
X1421490Y514619D01*
X1422265Y516495D01*
X1422575Y518370D01*
Y520661D01*
X1422265Y522536D01*
X1421490Y524203D01*
X1420560Y525036D01*
X1419475Y525453D01*
X1418235Y525036D01*
X1417305Y524203D01*
X1416685Y522953D01*
X1416375Y521286D01*
X1416685Y519828D01*
X1417460Y518370D01*
X1418390Y517536D01*
X1419475Y517328D01*
X1420715Y517744D01*
X1421645Y518786D01*
X1422575Y520661D01*
G01X1407075Y598803D02*
X1405835Y599011D01*
X1404750Y599844D01*
X1403820Y601095D01*
X1403200Y602553D01*
X1402890Y604220D01*
Y605886D01*
X1403200Y607553D01*
X1403820Y609011D01*
X1404750Y610261D01*
X1405835Y611095D01*
X1407075Y611303D01*
X1408315Y611095D01*
X1409400Y610261D01*
X1410330Y609011D01*
X1410950Y607553D01*
X1411260Y605886D01*
Y604220D01*
X1410950Y602553D01*
X1410330Y601095D01*
X1409400Y599844D01*
X1408315Y599011D01*
X1407075Y598803D01*
G01X1408315Y602136D02*
X1410175Y598803D01*
G01X1419475Y611303D02*
Y598803D01*
G01X1415910Y611303D02*
X1423040D01*
G01X1431875Y598803D02*
Y604428D01*
X1428775Y611303D01*
G01X1434975D02*
X1431875Y604428D01*
G01X1406765Y569153D02*
X1407075Y571861D01*
X1407540Y574153D01*
X1408160Y576236D01*
X1408935Y578528D01*
X1410175Y581653D01*
X1403975D01*
G01X1419475Y569153D02*
Y581653D01*
X1417615Y579153D01*
G01Y569153D02*
X1421335D01*
G01X1431875D02*
Y581653D01*
X1430015Y579153D01*
G01Y569153D02*
X1433735D01*
G01X20103Y-86244D02*
G03I-4291J0D01*
G01X0Y-87362D02*
G03X15000Y-102362I15000J0D01*
G01X0Y-11811D02*
Y-87362D01*
G01X3937Y-7874D02*
G03X0Y-11811I0J-3937D01*
G01X15748Y-7874D02*
X3937D01*
G01X0Y7874D02*
G03X7874Y0I7874J0D01*
G01X818897D02*
X7874D01*
G01X0Y7874D02*
Y562992D01*
G01X7874Y570866D02*
G03X0Y562992I0J-7874D01*
G01X7874Y570866D02*
X326781D01*
G01X312004Y-102362D02*
X15000D01*
G01X30560Y2455D02*
Y6455D01*
X32160D01*
X32693Y6255D01*
X33093Y5788D01*
X33226Y5255D01*
X33093Y4722D01*
X32760Y4322D01*
X32160Y4122D01*
X30560D01*
G01X35560Y2455D02*
Y5122D01*
G01Y4588D02*
X35893Y4855D01*
X36226Y5055D01*
X36693Y5122D01*
X37026Y5055D01*
X37426Y4855D01*
G01X40093Y4255D02*
X42226D01*
X42026Y4722D01*
X41693Y4988D01*
X41226Y5122D01*
X40760Y5055D01*
X40360Y4855D01*
X40093Y4388D01*
X39960Y3988D01*
Y3588D01*
X40093Y3188D01*
X40426Y2788D01*
X40826Y2522D01*
X41293Y2455D01*
X41760Y2588D01*
X42226Y2988D01*
G01X44693Y2922D02*
X45026Y2655D01*
X45493Y2455D01*
X45893D01*
X46293Y2588D01*
X46560Y2788D01*
X46693Y3055D01*
X46626Y3455D01*
X46360Y3655D01*
X45160Y4055D01*
X44893Y4522D01*
X45026Y4855D01*
X45293Y5055D01*
X45693Y5122D01*
X46093Y5055D01*
X46493Y4855D01*
G01X49293Y2922D02*
X49626Y2655D01*
X50093Y2455D01*
X50493D01*
X50893Y2588D01*
X51160Y2788D01*
X51293Y3055D01*
X51226Y3455D01*
X50960Y3655D01*
X49760Y4055D01*
X49493Y4522D01*
X49626Y4855D01*
X49893Y5055D01*
X50293Y5122D01*
X50693Y5055D01*
X51093Y4855D01*
G01X54026Y3788D02*
X55760D01*
G01X59093Y2455D02*
Y5855D01*
X59226Y6188D01*
X59493Y6388D01*
X59893Y6455D01*
X60293Y6322D01*
X60493Y5988D01*
G01X59693Y4855D02*
X58360D01*
G01X64093Y5122D02*
Y2455D01*
G01Y6188D02*
X63960Y6255D01*
Y6388D01*
X64093Y6455D01*
X64226Y6388D01*
Y6255D01*
X64093Y6188D01*
G01X68693Y6455D02*
Y2455D01*
G01X67760Y5122D02*
X69626D01*
G01X76560Y2455D02*
Y6455D01*
X78160D01*
X78693Y6255D01*
X79093Y5788D01*
X79226Y5255D01*
X79093Y4722D01*
X78760Y4322D01*
X78160Y4122D01*
X76560D01*
G01X82493Y6455D02*
Y2455D01*
G01X80960Y6455D02*
X84026D01*
G01X85693Y2455D02*
Y6455D01*
G01X88493D02*
Y2455D01*
G01Y4455D02*
X85693D01*
G01X95160Y2455D02*
Y6455D01*
G01X97293Y5122D02*
X95160Y3588D01*
G01X96026Y4188D02*
X97426Y2455D01*
G01X99893Y4255D02*
X102026D01*
X101826Y4722D01*
X101493Y4988D01*
X101026Y5122D01*
X100560Y5055D01*
X100160Y4855D01*
X99893Y4388D01*
X99760Y3988D01*
Y3588D01*
X99893Y3188D01*
X100226Y2788D01*
X100626Y2522D01*
X101093Y2455D01*
X101560Y2588D01*
X102026Y2988D01*
G01X104493Y4255D02*
X106626D01*
X106426Y4722D01*
X106093Y4988D01*
X105626Y5122D01*
X105160Y5055D01*
X104760Y4855D01*
X104493Y4388D01*
X104360Y3988D01*
Y3588D01*
X104493Y3188D01*
X104826Y2788D01*
X105226Y2522D01*
X105693Y2455D01*
X106160Y2588D01*
X106626Y2988D01*
G01X108893Y1122D02*
Y5122D01*
G01Y4522D02*
X109226Y4855D01*
X109560Y5055D01*
X110093Y5122D01*
X110560Y5055D01*
X111026Y4722D01*
X111226Y4255D01*
X111293Y3788D01*
X111226Y3322D01*
X111026Y2855D01*
X110626Y2588D01*
X110093Y2455D01*
X109626Y2522D01*
X109160Y2722D01*
X108893Y2988D01*
G01X118160Y2455D02*
Y6455D01*
G01Y4522D02*
X118493Y4855D01*
X118826Y5055D01*
X119360Y5122D01*
X119760Y5055D01*
X120226Y4788D01*
X120426Y4388D01*
Y2455D01*
G01X123893D02*
X123493Y2522D01*
X123093Y2788D01*
X122826Y3255D01*
X122693Y3788D01*
X122826Y4322D01*
X123093Y4788D01*
X123493Y5055D01*
X123893Y5122D01*
X124293Y5055D01*
X124693Y4788D01*
X124960Y4322D01*
X125026Y3788D01*
X124960Y3255D01*
X124693Y2788D01*
X124293Y2522D01*
X123893Y2455D01*
G01X128493D02*
Y6455D01*
G01X132093Y4255D02*
X134226D01*
X134026Y4722D01*
X133693Y4988D01*
X133226Y5122D01*
X132760Y5055D01*
X132360Y4855D01*
X132093Y4388D01*
X131960Y3988D01*
Y3588D01*
X132093Y3188D01*
X132426Y2788D01*
X132826Y2522D01*
X133293Y2455D01*
X133760Y2588D01*
X134226Y2988D01*
G01X141293Y2922D02*
X141626Y2655D01*
X142093Y2455D01*
X142493D01*
X142893Y2588D01*
X143160Y2788D01*
X143293Y3055D01*
X143226Y3455D01*
X142960Y3655D01*
X141760Y4055D01*
X141493Y4522D01*
X141626Y4855D01*
X141893Y5055D01*
X142293Y5122D01*
X142693Y5055D01*
X143093Y4855D01*
G01X146893Y5122D02*
Y2455D01*
G01Y6188D02*
X146760Y6255D01*
Y6388D01*
X146893Y6455D01*
X147026Y6388D01*
Y6255D01*
X146893Y6188D01*
G01X150493Y5122D02*
X152493D01*
X150493Y2455D01*
X152493D01*
G01X155093Y4255D02*
X157226D01*
X157026Y4722D01*
X156693Y4988D01*
X156226Y5122D01*
X155760Y5055D01*
X155360Y4855D01*
X155093Y4388D01*
X154960Y3988D01*
Y3588D01*
X155093Y3188D01*
X155426Y2788D01*
X155826Y2522D01*
X156293Y2455D01*
X156760Y2588D01*
X157226Y2988D01*
G01X165293Y6455D02*
Y2455D01*
G01X164360Y5122D02*
X166226D01*
G01X169893Y2455D02*
X169493Y2522D01*
X169093Y2788D01*
X168826Y3255D01*
X168693Y3788D01*
X168826Y4322D01*
X169093Y4788D01*
X169493Y5055D01*
X169893Y5122D01*
X170293Y5055D01*
X170693Y4788D01*
X170960Y4322D01*
X171026Y3788D01*
X170960Y3255D01*
X170693Y2788D01*
X170293Y2522D01*
X169893Y2455D01*
G01X174493D02*
Y6455D01*
G01X178093Y4255D02*
X180226D01*
X180026Y4722D01*
X179693Y4988D01*
X179226Y5122D01*
X178760Y5055D01*
X178360Y4855D01*
X178093Y4388D01*
X177960Y3988D01*
Y3588D01*
X178093Y3188D01*
X178426Y2788D01*
X178826Y2522D01*
X179293Y2455D01*
X179760Y2588D01*
X180226Y2988D01*
G01X182760Y2455D02*
Y5122D01*
G01Y4588D02*
X183093Y4855D01*
X183426Y5055D01*
X183893Y5122D01*
X184226Y5055D01*
X184626Y4855D01*
G01X189493Y2455D02*
Y5122D01*
G01Y4655D02*
X189226Y4922D01*
X188826Y5055D01*
X188360Y5122D01*
X187893Y4988D01*
X187493Y4722D01*
X187226Y4322D01*
X187093Y3788D01*
X187226Y3255D01*
X187493Y2855D01*
X187893Y2588D01*
X188360Y2455D01*
X188826Y2522D01*
X189226Y2722D01*
X189493Y2988D01*
G01X191760Y2455D02*
Y5122D01*
G01Y4455D02*
X192026Y4788D01*
X192426Y5055D01*
X192960Y5122D01*
X193426Y5055D01*
X193826Y4788D01*
X194026Y4322D01*
Y2455D01*
G01X198560Y4788D02*
X198093Y5055D01*
X197693Y5122D01*
X197160Y4988D01*
X196760Y4722D01*
X196493Y4255D01*
X196426Y3788D01*
X196493Y3322D01*
X196760Y2922D01*
X197160Y2588D01*
X197693Y2455D01*
X198160Y2588D01*
X198560Y2855D01*
G01X201093Y4255D02*
X203226D01*
X203026Y4722D01*
X202693Y4988D01*
X202226Y5122D01*
X201760Y5055D01*
X201360Y4855D01*
X201093Y4388D01*
X200960Y3988D01*
Y3588D01*
X201093Y3188D01*
X201426Y2788D01*
X201826Y2522D01*
X202293Y2455D01*
X202760Y2588D01*
X203226Y2988D01*
G01X210560Y3788D02*
X212160D01*
G01X211293Y4655D02*
Y2922D01*
G01X214693Y2322D02*
X217093Y6455D01*
G01X219626Y3788D02*
X221360D01*
G01X223826Y5788D02*
X224226Y6188D01*
X224693Y6388D01*
X225226Y6455D01*
X225893Y6322D01*
X226360Y5988D01*
X226493Y5588D01*
X226426Y5188D01*
X226160Y4855D01*
X224826Y4188D01*
X224226Y3722D01*
X223826Y3055D01*
X223693Y2455D01*
X226493D01*
G01X232293D02*
Y5122D01*
G01Y4388D02*
X232493Y4722D01*
X232826Y4988D01*
X233293Y5122D01*
X233760Y4988D01*
X234093Y4722D01*
X234293Y4388D01*
Y2455D01*
G01Y4388D02*
X234493Y4722D01*
X234826Y4988D01*
X235293Y5122D01*
X235760Y4988D01*
X236093Y4722D01*
X236293Y4322D01*
Y2455D01*
G01X238893Y5122D02*
Y2455D01*
G01Y6188D02*
X238760Y6255D01*
Y6388D01*
X238893Y6455D01*
X239026Y6388D01*
Y6255D01*
X238893Y6188D01*
G01X243493Y2455D02*
Y6455D01*
G01X75669Y0D02*
X193669D01*
G01X46456D02*
G03Y-7874I0J-3937D01*
G01X15748D02*
G03Y0I0J3937D01*
G01X287400Y-7874D02*
X46456D01*
G01X40452Y499724D02*
G03I-3051J0D01*
G01X41535Y535157D02*
G03I-4134J0D01*
G01X44685Y517441D02*
G03I-7284J0D01*
G01X121082Y39055D02*
G03I-5019J0D01*
G01X120807Y14567D02*
G03I-4744J0D01*
G01X142615Y-11756D02*
X143148Y-12089D01*
X143748Y-12289D01*
X144282D01*
X144815Y-12089D01*
X145215Y-11756D01*
X145415Y-11289D01*
X145282Y-10822D01*
X144948Y-10422D01*
X144348Y-10156D01*
X143548Y-10022D01*
X143082Y-9756D01*
X142882Y-9289D01*
X143015Y-8822D01*
X143348Y-8489D01*
X143815Y-8289D01*
X144282D01*
X144748Y-8422D01*
X145148Y-8756D01*
G01X148615Y-12289D02*
Y-8289D01*
G01X153215Y-9622D02*
Y-12289D01*
G01Y-8556D02*
X153082Y-8489D01*
Y-8356D01*
X153215Y-8289D01*
X153348Y-8356D01*
Y-8489D01*
X153215Y-8556D01*
G01X157815Y-8289D02*
Y-12289D01*
G01X156882Y-9622D02*
X158748D01*
G01X142469Y16603D02*
X161467D01*
Y56467D01*
X142469D01*
Y16603D01*
G01X150797Y-511D02*
X148797Y-2511D01*
X152797D01*
X150797Y-511D01*
Y-8511D01*
G01X152441Y15835D02*
X150441Y13835D01*
X154441D01*
X152441Y15835D01*
Y7835D01*
G01X319878Y-102362D02*
G03X312004I-3937J0D01*
G01X811771D02*
X319878D01*
G01X622835Y0D02*
X308662D01*
G01X326770D02*
G03Y-7874I0J-3937D01*
G01X287400D02*
G03Y0I0J3937D01*
G01X513719Y485130D02*
Y481130D01*
X512119D01*
X511586Y481330D01*
X511186Y481797D01*
X511053Y482330D01*
X511186Y482863D01*
X511519Y483263D01*
X512119Y483463D01*
X513719D01*
G01X508719Y485130D02*
Y482463D01*
G01Y482997D02*
X508386Y482730D01*
X508053Y482530D01*
X507586Y482463D01*
X507253Y482530D01*
X506853Y482730D01*
G01X504186Y483330D02*
X502053D01*
X502253Y482863D01*
X502586Y482597D01*
X503053Y482463D01*
X503519Y482530D01*
X503919Y482730D01*
X504186Y483197D01*
X504319Y483597D01*
Y483997D01*
X504186Y484397D01*
X503853Y484797D01*
X503453Y485063D01*
X502986Y485130D01*
X502519Y484997D01*
X502053Y484597D01*
G01X499586Y484663D02*
X499253Y484930D01*
X498786Y485130D01*
X498386D01*
X497986Y484997D01*
X497719Y484797D01*
X497586Y484530D01*
X497653Y484130D01*
X497919Y483930D01*
X499119Y483530D01*
X499386Y483063D01*
X499253Y482730D01*
X498986Y482530D01*
X498586Y482463D01*
X498186Y482530D01*
X497786Y482730D01*
G01X494986Y484663D02*
X494653Y484930D01*
X494186Y485130D01*
X493786D01*
X493386Y484997D01*
X493119Y484797D01*
X492986Y484530D01*
X493053Y484130D01*
X493319Y483930D01*
X494519Y483530D01*
X494786Y483063D01*
X494653Y482730D01*
X494386Y482530D01*
X493986Y482463D01*
X493586Y482530D01*
X493186Y482730D01*
G01X490253Y483797D02*
X488519D01*
G01X485186Y485130D02*
Y481730D01*
X485053Y481397D01*
X484786Y481197D01*
X484386Y481130D01*
X483986Y481263D01*
X483786Y481597D01*
G01X484586Y482730D02*
X485919D01*
G01X480186Y482463D02*
Y485130D01*
G01Y481397D02*
X480319Y481330D01*
Y481197D01*
X480186Y481130D01*
X480053Y481197D01*
Y481330D01*
X480186Y481397D01*
G01X475586Y481130D02*
Y485130D01*
G01X476519Y482463D02*
X474653D01*
G01X467719Y485130D02*
Y481130D01*
X466119D01*
X465586Y481330D01*
X465186Y481797D01*
X465053Y482330D01*
X465186Y482863D01*
X465519Y483263D01*
X466119Y483463D01*
X467719D01*
G01X461786Y481130D02*
Y485130D01*
G01X463319Y481130D02*
X460253D01*
G01X458586Y485130D02*
Y481130D01*
G01X455786D02*
Y485130D01*
G01Y483130D02*
X458586D01*
G01X449119Y485130D02*
Y481130D01*
G01X446986Y482463D02*
X449119Y483997D01*
G01X448253Y483397D02*
X446853Y485130D01*
G01X444386Y483330D02*
X442253D01*
X442453Y482863D01*
X442786Y482597D01*
X443253Y482463D01*
X443719Y482530D01*
X444119Y482730D01*
X444386Y483197D01*
X444519Y483597D01*
Y483997D01*
X444386Y484397D01*
X444053Y484797D01*
X443653Y485063D01*
X443186Y485130D01*
X442719Y484997D01*
X442253Y484597D01*
G01X439786Y483330D02*
X437653D01*
X437853Y482863D01*
X438186Y482597D01*
X438653Y482463D01*
X439119Y482530D01*
X439519Y482730D01*
X439786Y483197D01*
X439919Y483597D01*
Y483997D01*
X439786Y484397D01*
X439453Y484797D01*
X439053Y485063D01*
X438586Y485130D01*
X438119Y484997D01*
X437653Y484597D01*
G01X435386Y486463D02*
Y482463D01*
G01Y483063D02*
X435053Y482730D01*
X434719Y482530D01*
X434186Y482463D01*
X433719Y482530D01*
X433253Y482863D01*
X433053Y483330D01*
X432986Y483797D01*
X433053Y484263D01*
X433253Y484730D01*
X433653Y484997D01*
X434186Y485130D01*
X434653Y485063D01*
X435119Y484863D01*
X435386Y484597D01*
G01X426119Y485130D02*
Y481130D01*
G01Y483063D02*
X425786Y482730D01*
X425453Y482530D01*
X424919Y482463D01*
X424519Y482530D01*
X424053Y482797D01*
X423853Y483197D01*
Y485130D01*
G01X420386D02*
X420786Y485063D01*
X421186Y484797D01*
X421453Y484330D01*
X421586Y483797D01*
X421453Y483263D01*
X421186Y482797D01*
X420786Y482530D01*
X420386Y482463D01*
X419986Y482530D01*
X419586Y482797D01*
X419319Y483263D01*
X419253Y483797D01*
X419319Y484330D01*
X419586Y484797D01*
X419986Y485063D01*
X420386Y485130D01*
G01X415786D02*
Y481130D01*
G01X412186Y483330D02*
X410053D01*
X410253Y482863D01*
X410586Y482597D01*
X411053Y482463D01*
X411519Y482530D01*
X411919Y482730D01*
X412186Y483197D01*
X412319Y483597D01*
Y483997D01*
X412186Y484397D01*
X411853Y484797D01*
X411453Y485063D01*
X410986Y485130D01*
X410519Y484997D01*
X410053Y484597D01*
G01X402986Y484663D02*
X402653Y484930D01*
X402186Y485130D01*
X401786D01*
X401386Y484997D01*
X401119Y484797D01*
X400986Y484530D01*
X401053Y484130D01*
X401319Y483930D01*
X402519Y483530D01*
X402786Y483063D01*
X402653Y482730D01*
X402386Y482530D01*
X401986Y482463D01*
X401586Y482530D01*
X401186Y482730D01*
G01X397386Y482463D02*
Y485130D01*
G01Y481397D02*
X397519Y481330D01*
Y481197D01*
X397386Y481130D01*
X397253Y481197D01*
Y481330D01*
X397386Y481397D01*
G01X393786Y482463D02*
X391786D01*
X393786Y485130D01*
X391786D01*
G01X389186Y483330D02*
X387053D01*
X387253Y482863D01*
X387586Y482597D01*
X388053Y482463D01*
X388519Y482530D01*
X388919Y482730D01*
X389186Y483197D01*
X389319Y483597D01*
Y483997D01*
X389186Y484397D01*
X388853Y484797D01*
X388453Y485063D01*
X387986Y485130D01*
X387519Y484997D01*
X387053Y484597D01*
G01X378986Y481130D02*
Y485130D01*
G01X379919Y482463D02*
X378053D01*
G01X374386Y485130D02*
X374786Y485063D01*
X375186Y484797D01*
X375453Y484330D01*
X375586Y483797D01*
X375453Y483263D01*
X375186Y482797D01*
X374786Y482530D01*
X374386Y482463D01*
X373986Y482530D01*
X373586Y482797D01*
X373319Y483263D01*
X373253Y483797D01*
X373319Y484330D01*
X373586Y484797D01*
X373986Y485063D01*
X374386Y485130D01*
G01X369786D02*
Y481130D01*
G01X366186Y483330D02*
X364053D01*
X364253Y482863D01*
X364586Y482597D01*
X365053Y482463D01*
X365519Y482530D01*
X365919Y482730D01*
X366186Y483197D01*
X366319Y483597D01*
Y483997D01*
X366186Y484397D01*
X365853Y484797D01*
X365453Y485063D01*
X364986Y485130D01*
X364519Y484997D01*
X364053Y484597D01*
G01X361519Y485130D02*
Y482463D01*
G01Y482997D02*
X361186Y482730D01*
X360853Y482530D01*
X360386Y482463D01*
X360053Y482530D01*
X359653Y482730D01*
G01X354786Y485130D02*
Y482463D01*
G01Y482930D02*
X355053Y482663D01*
X355453Y482530D01*
X355919Y482463D01*
X356386Y482597D01*
X356786Y482863D01*
X357053Y483263D01*
X357186Y483797D01*
X357053Y484330D01*
X356786Y484730D01*
X356386Y484997D01*
X355919Y485130D01*
X355453Y485063D01*
X355053Y484863D01*
X354786Y484597D01*
G01X352519Y485130D02*
Y482463D01*
G01Y483130D02*
X352253Y482797D01*
X351853Y482530D01*
X351319Y482463D01*
X350853Y482530D01*
X350453Y482797D01*
X350253Y483263D01*
Y485130D01*
G01X345719Y482797D02*
X346186Y482530D01*
X346586Y482463D01*
X347119Y482597D01*
X347519Y482863D01*
X347786Y483330D01*
X347853Y483797D01*
X347786Y484263D01*
X347519Y484663D01*
X347119Y484997D01*
X346586Y485130D01*
X346119Y484997D01*
X345719Y484730D01*
G01X343186Y483330D02*
X341053D01*
X341253Y482863D01*
X341586Y482597D01*
X342053Y482463D01*
X342519Y482530D01*
X342919Y482730D01*
X343186Y483197D01*
X343319Y483597D01*
Y483997D01*
X343186Y484397D01*
X342853Y484797D01*
X342453Y485063D01*
X341986Y485130D01*
X341519Y484997D01*
X341053Y484597D01*
G01X333719Y483797D02*
X332119D01*
G01X332986Y482930D02*
Y484663D01*
G01X329586Y485263D02*
X327186Y481130D01*
G01X324653Y483797D02*
X322919D01*
G01X320453Y481797D02*
X320053Y481397D01*
X319586Y481197D01*
X319053Y481130D01*
X318386Y481263D01*
X317919Y481597D01*
X317786Y481997D01*
X317853Y482397D01*
X318119Y482730D01*
X319453Y483397D01*
X320053Y483863D01*
X320453Y484530D01*
X320586Y485130D01*
X317786D01*
G01X316586D02*
Y482463D01*
G01Y483197D02*
X316386Y482863D01*
X316053Y482597D01*
X315586Y482463D01*
X315119Y482597D01*
X314786Y482863D01*
X314586Y483197D01*
Y485130D01*
G01Y483197D02*
X314386Y482863D01*
X314053Y482597D01*
X313586Y482463D01*
X313119Y482597D01*
X312786Y482863D01*
X312586Y483263D01*
Y485130D01*
G01X309986Y482463D02*
Y485130D01*
G01Y481397D02*
X310119Y481330D01*
Y481197D01*
X309986Y481130D01*
X309853Y481197D01*
Y481330D01*
X309986Y481397D01*
G01X305386Y485130D02*
Y481130D01*
G01X301786Y484663D02*
X301453Y484930D01*
X300986Y485130D01*
X300586D01*
X300186Y484997D01*
X299919Y484797D01*
X299786Y484530D01*
X299853Y484130D01*
X300119Y483930D01*
X301319Y483530D01*
X301586Y483063D01*
X301453Y482730D01*
X301186Y482530D01*
X300786Y482463D01*
X300386Y482530D01*
X299986Y482730D01*
G01X302165Y531496D02*
G03I-6890J0D01*
G01X341350Y-12639D02*
Y-8639D01*
X342950D01*
X343483Y-8839D01*
X343883Y-9306D01*
X344016Y-9839D01*
X343883Y-10372D01*
X343550Y-10772D01*
X342950Y-10972D01*
X341350D01*
G01X346350Y-12639D02*
Y-9972D01*
G01Y-10506D02*
X346683Y-10239D01*
X347016Y-10039D01*
X347483Y-9972D01*
X347816Y-10039D01*
X348216Y-10239D01*
G01X350883Y-10839D02*
X353016D01*
X352816Y-10372D01*
X352483Y-10106D01*
X352016Y-9972D01*
X351550Y-10039D01*
X351150Y-10239D01*
X350883Y-10706D01*
X350750Y-11106D01*
Y-11506D01*
X350883Y-11906D01*
X351216Y-12306D01*
X351616Y-12572D01*
X352083Y-12639D01*
X352550Y-12506D01*
X353016Y-12106D01*
G01X355483Y-12172D02*
X355816Y-12439D01*
X356283Y-12639D01*
X356683D01*
X357083Y-12506D01*
X357350Y-12306D01*
X357483Y-12039D01*
X357416Y-11639D01*
X357150Y-11439D01*
X355950Y-11039D01*
X355683Y-10572D01*
X355816Y-10239D01*
X356083Y-10039D01*
X356483Y-9972D01*
X356883Y-10039D01*
X357283Y-10239D01*
G01X360083Y-12172D02*
X360416Y-12439D01*
X360883Y-12639D01*
X361283D01*
X361683Y-12506D01*
X361950Y-12306D01*
X362083Y-12039D01*
X362016Y-11639D01*
X361750Y-11439D01*
X360550Y-11039D01*
X360283Y-10572D01*
X360416Y-10239D01*
X360683Y-10039D01*
X361083Y-9972D01*
X361483Y-10039D01*
X361883Y-10239D01*
G01X364816Y-11306D02*
X366550D01*
G01X369883Y-12639D02*
Y-9239D01*
X370016Y-8906D01*
X370283Y-8706D01*
X370683Y-8639D01*
X371083Y-8772D01*
X371283Y-9106D01*
G01X370483Y-10239D02*
X369150D01*
G01X374883Y-9972D02*
Y-12639D01*
G01Y-8906D02*
X374750Y-8839D01*
Y-8706D01*
X374883Y-8639D01*
X375016Y-8706D01*
Y-8839D01*
X374883Y-8906D01*
G01X379483Y-8639D02*
Y-12639D01*
G01X378550Y-9972D02*
X380416D01*
G01X387350Y-12639D02*
Y-8639D01*
X388950D01*
X389483Y-8839D01*
X389883Y-9306D01*
X390016Y-9839D01*
X389883Y-10372D01*
X389550Y-10772D01*
X388950Y-10972D01*
X387350D01*
G01X393283Y-8639D02*
Y-12639D01*
G01X391750Y-8639D02*
X394816D01*
G01X396483Y-12639D02*
Y-8639D01*
G01X399283D02*
Y-12639D01*
G01Y-10639D02*
X396483D01*
G01X405950Y-12639D02*
Y-8639D01*
G01X408083Y-9972D02*
X405950Y-11506D01*
G01X406816Y-10906D02*
X408216Y-12639D01*
G01X410683Y-10839D02*
X412816D01*
X412616Y-10372D01*
X412283Y-10106D01*
X411816Y-9972D01*
X411350Y-10039D01*
X410950Y-10239D01*
X410683Y-10706D01*
X410550Y-11106D01*
Y-11506D01*
X410683Y-11906D01*
X411016Y-12306D01*
X411416Y-12572D01*
X411883Y-12639D01*
X412350Y-12506D01*
X412816Y-12106D01*
G01X415283Y-10839D02*
X417416D01*
X417216Y-10372D01*
X416883Y-10106D01*
X416416Y-9972D01*
X415950Y-10039D01*
X415550Y-10239D01*
X415283Y-10706D01*
X415150Y-11106D01*
Y-11506D01*
X415283Y-11906D01*
X415616Y-12306D01*
X416016Y-12572D01*
X416483Y-12639D01*
X416950Y-12506D01*
X417416Y-12106D01*
G01X419683Y-13972D02*
Y-9972D01*
G01Y-10572D02*
X420016Y-10239D01*
X420350Y-10039D01*
X420883Y-9972D01*
X421350Y-10039D01*
X421816Y-10372D01*
X422016Y-10839D01*
X422083Y-11306D01*
X422016Y-11772D01*
X421816Y-12239D01*
X421416Y-12506D01*
X420883Y-12639D01*
X420416Y-12572D01*
X419950Y-12372D01*
X419683Y-12106D01*
G01X428950Y-12639D02*
Y-8639D01*
G01Y-10572D02*
X429283Y-10239D01*
X429616Y-10039D01*
X430150Y-9972D01*
X430550Y-10039D01*
X431016Y-10306D01*
X431216Y-10706D01*
Y-12639D01*
G01X434683D02*
X434283Y-12572D01*
X433883Y-12306D01*
X433616Y-11839D01*
X433483Y-11306D01*
X433616Y-10772D01*
X433883Y-10306D01*
X434283Y-10039D01*
X434683Y-9972D01*
X435083Y-10039D01*
X435483Y-10306D01*
X435750Y-10772D01*
X435816Y-11306D01*
X435750Y-11839D01*
X435483Y-12306D01*
X435083Y-12572D01*
X434683Y-12639D01*
G01X439283D02*
Y-8639D01*
G01X442883Y-10839D02*
X445016D01*
X444816Y-10372D01*
X444483Y-10106D01*
X444016Y-9972D01*
X443550Y-10039D01*
X443150Y-10239D01*
X442883Y-10706D01*
X442750Y-11106D01*
Y-11506D01*
X442883Y-11906D01*
X443216Y-12306D01*
X443616Y-12572D01*
X444083Y-12639D01*
X444550Y-12506D01*
X445016Y-12106D01*
G01X452083Y-12172D02*
X452416Y-12439D01*
X452883Y-12639D01*
X453283D01*
X453683Y-12506D01*
X453950Y-12306D01*
X454083Y-12039D01*
X454016Y-11639D01*
X453750Y-11439D01*
X452550Y-11039D01*
X452283Y-10572D01*
X452416Y-10239D01*
X452683Y-10039D01*
X453083Y-9972D01*
X453483Y-10039D01*
X453883Y-10239D01*
G01X457683Y-9972D02*
Y-12639D01*
G01Y-8906D02*
X457550Y-8839D01*
Y-8706D01*
X457683Y-8639D01*
X457816Y-8706D01*
Y-8839D01*
X457683Y-8906D01*
G01X461283Y-9972D02*
X463283D01*
X461283Y-12639D01*
X463283D01*
G01X465883Y-10839D02*
X468016D01*
X467816Y-10372D01*
X467483Y-10106D01*
X467016Y-9972D01*
X466550Y-10039D01*
X466150Y-10239D01*
X465883Y-10706D01*
X465750Y-11106D01*
Y-11506D01*
X465883Y-11906D01*
X466216Y-12306D01*
X466616Y-12572D01*
X467083Y-12639D01*
X467550Y-12506D01*
X468016Y-12106D01*
G01X476083Y-8639D02*
Y-12639D01*
G01X475150Y-9972D02*
X477016D01*
G01X480683Y-12639D02*
X480283Y-12572D01*
X479883Y-12306D01*
X479616Y-11839D01*
X479483Y-11306D01*
X479616Y-10772D01*
X479883Y-10306D01*
X480283Y-10039D01*
X480683Y-9972D01*
X481083Y-10039D01*
X481483Y-10306D01*
X481750Y-10772D01*
X481816Y-11306D01*
X481750Y-11839D01*
X481483Y-12306D01*
X481083Y-12572D01*
X480683Y-12639D01*
G01X485283D02*
Y-8639D01*
G01X488883Y-10839D02*
X491016D01*
X490816Y-10372D01*
X490483Y-10106D01*
X490016Y-9972D01*
X489550Y-10039D01*
X489150Y-10239D01*
X488883Y-10706D01*
X488750Y-11106D01*
Y-11506D01*
X488883Y-11906D01*
X489216Y-12306D01*
X489616Y-12572D01*
X490083Y-12639D01*
X490550Y-12506D01*
X491016Y-12106D01*
G01X493550Y-12639D02*
Y-9972D01*
G01Y-10506D02*
X493883Y-10239D01*
X494216Y-10039D01*
X494683Y-9972D01*
X495016Y-10039D01*
X495416Y-10239D01*
G01X500283Y-12639D02*
Y-9972D01*
G01Y-10439D02*
X500016Y-10172D01*
X499616Y-10039D01*
X499150Y-9972D01*
X498683Y-10106D01*
X498283Y-10372D01*
X498016Y-10772D01*
X497883Y-11306D01*
X498016Y-11839D01*
X498283Y-12239D01*
X498683Y-12506D01*
X499150Y-12639D01*
X499616Y-12572D01*
X500016Y-12372D01*
X500283Y-12106D01*
G01X502550Y-12639D02*
Y-9972D01*
G01Y-10639D02*
X502816Y-10306D01*
X503216Y-10039D01*
X503750Y-9972D01*
X504216Y-10039D01*
X504616Y-10306D01*
X504816Y-10772D01*
Y-12639D01*
G01X509350Y-10306D02*
X508883Y-10039D01*
X508483Y-9972D01*
X507950Y-10106D01*
X507550Y-10372D01*
X507283Y-10839D01*
X507216Y-11306D01*
X507283Y-11772D01*
X507550Y-12172D01*
X507950Y-12506D01*
X508483Y-12639D01*
X508950Y-12506D01*
X509350Y-12239D01*
G01X511883Y-10839D02*
X514016D01*
X513816Y-10372D01*
X513483Y-10106D01*
X513016Y-9972D01*
X512550Y-10039D01*
X512150Y-10239D01*
X511883Y-10706D01*
X511750Y-11106D01*
Y-11506D01*
X511883Y-11906D01*
X512216Y-12306D01*
X512616Y-12572D01*
X513083Y-12639D01*
X513550Y-12506D01*
X514016Y-12106D01*
G01X521350Y-11306D02*
X522950D01*
G01X522083Y-10439D02*
Y-12172D01*
G01X525483Y-12772D02*
X527883Y-8639D01*
G01X530416Y-11306D02*
X532150D01*
G01X534616Y-9306D02*
X535016Y-8906D01*
X535483Y-8706D01*
X536016Y-8639D01*
X536683Y-8772D01*
X537150Y-9106D01*
X537283Y-9506D01*
X537216Y-9906D01*
X536950Y-10239D01*
X535616Y-10906D01*
X535016Y-11372D01*
X534616Y-12039D01*
X534483Y-12639D01*
X537283D01*
G01X543083D02*
Y-9972D01*
G01Y-10706D02*
X543283Y-10372D01*
X543616Y-10106D01*
X544083Y-9972D01*
X544550Y-10106D01*
X544883Y-10372D01*
X545083Y-10706D01*
Y-12639D01*
G01Y-10706D02*
X545283Y-10372D01*
X545616Y-10106D01*
X546083Y-9972D01*
X546550Y-10106D01*
X546883Y-10372D01*
X547083Y-10772D01*
Y-12639D01*
G01X549683Y-9972D02*
Y-12639D01*
G01Y-8906D02*
X549550Y-8839D01*
Y-8706D01*
X549683Y-8639D01*
X549816Y-8706D01*
Y-8839D01*
X549683Y-8906D01*
G01X554283Y-12639D02*
Y-8639D01*
G01X557883Y-12172D02*
X558216Y-12439D01*
X558683Y-12639D01*
X559083D01*
X559483Y-12506D01*
X559750Y-12306D01*
X559883Y-12039D01*
X559816Y-11639D01*
X559550Y-11439D01*
X558350Y-11039D01*
X558083Y-10572D01*
X558216Y-10239D01*
X558483Y-10039D01*
X558883Y-9972D01*
X559283Y-10039D01*
X559683Y-10239D01*
G01X336083Y55650D02*
X589114D01*
Y3406D01*
X336083D01*
Y55650D01*
G01X597707Y-7874D02*
X326770D01*
G01X379921Y156220D02*
G03I-5906J0D01*
G01X399325Y405034D02*
X427447D01*
Y455480D01*
X442158D01*
Y465780D01*
X384614D01*
Y455480D01*
X399325D01*
Y405034D01*
G01X342529Y530315D02*
G03X334655I-3937J0D01*
G01X342529Y520720D02*
G03X352474Y509057I11811J0D01*
G01X334655Y520720D02*
G03X351230Y501282I19685J0D01*
G01X384484Y503937D02*
X352475Y509057D01*
G01X383858Y496063D02*
X351231Y501282D01*
G01X442287Y503937D02*
X384484D01*
G01X442913Y496063D02*
X383858D01*
G01X342529Y530315D02*
Y520720D01*
G01X334655Y562992D02*
Y520720D01*
G01X346466Y570866D02*
G03X342529Y566929I0J-3937D01*
G01X334655Y555512D02*
G03X342529I3937J0D01*
G01X346466Y570866D02*
X480325D01*
G01X334655Y562992D02*
G03X326781Y570866I-7874J0D01*
G01X342529Y566929D02*
Y555512D01*
G01X440675Y-24061D02*
X441208Y-24394D01*
X441808Y-24594D01*
X442342D01*
X442875Y-24394D01*
X443275Y-24061D01*
X443475Y-23594D01*
X443342Y-23127D01*
X443008Y-22727D01*
X442408Y-22461D01*
X441608Y-22327D01*
X441142Y-22061D01*
X440942Y-21594D01*
X441075Y-21127D01*
X441408Y-20794D01*
X441875Y-20594D01*
X442342D01*
X442808Y-20727D01*
X443208Y-21061D01*
G01X446675Y-24594D02*
Y-20594D01*
G01X451275Y-21927D02*
Y-24594D01*
G01Y-20861D02*
X451142Y-20794D01*
Y-20661D01*
X451275Y-20594D01*
X451408Y-20661D01*
Y-20794D01*
X451275Y-20861D01*
G01X455875Y-20594D02*
Y-24594D01*
G01X454942Y-21927D02*
X456808D01*
G01X448583Y-19039D02*
Y-39D01*
X444583Y-4039D01*
X452583D01*
X448583Y-39D01*
G01X394533Y-6994D02*
Y2706D01*
X399533Y-2294D01*
X389533D01*
X394533Y2706D01*
G01X437136Y480980D02*
Y466230D01*
X441436Y470530D01*
X432836D01*
X437136Y466230D01*
G01X415943Y539991D02*
G03I-4291J0D01*
G01X474316Y509060D02*
X442287Y503937D01*
G01X475560Y501285D02*
X442913Y496063D01*
G01X492136Y530315D02*
G03X484262I-3937J0D01*
G01X474316Y509060D02*
G03X484262Y520723I-1865J11663D01*
G01X475560Y501285D02*
G03X492136Y520723I-3109J19438D01*
G01X484262Y530315D02*
Y520723D01*
G01X492136Y562992D02*
Y520723D01*
G01X484262Y566929D02*
G03X480325Y570866I-3937J0D01*
G01X484262Y555512D02*
G03X492136I3937J0D01*
G01X500010Y570866D02*
G03X492136Y562992I0J-7874D01*
G01X500010Y570866D02*
X818897D01*
G01X484262Y566929D02*
Y555512D01*
G01X537401Y371299D02*
G03I-5905J0D01*
G01X538386Y531496D02*
G03I-6890J0D01*
G01X623328Y-15839D02*
Y-11839D01*
X624928D01*
X625461Y-12039D01*
X625861Y-12506D01*
X625994Y-13039D01*
X625861Y-13572D01*
X625528Y-13972D01*
X624928Y-14172D01*
X623328D01*
G01X628328Y-15839D02*
Y-13172D01*
G01Y-13706D02*
X628661Y-13439D01*
X628994Y-13239D01*
X629461Y-13172D01*
X629794Y-13239D01*
X630194Y-13439D01*
G01X632861Y-14039D02*
X634994D01*
X634794Y-13572D01*
X634461Y-13306D01*
X633994Y-13172D01*
X633528Y-13239D01*
X633128Y-13439D01*
X632861Y-13906D01*
X632728Y-14306D01*
Y-14706D01*
X632861Y-15106D01*
X633194Y-15506D01*
X633594Y-15772D01*
X634061Y-15839D01*
X634528Y-15706D01*
X634994Y-15306D01*
G01X637461Y-15372D02*
X637794Y-15639D01*
X638261Y-15839D01*
X638661D01*
X639061Y-15706D01*
X639328Y-15506D01*
X639461Y-15239D01*
X639394Y-14839D01*
X639128Y-14639D01*
X637928Y-14239D01*
X637661Y-13772D01*
X637794Y-13439D01*
X638061Y-13239D01*
X638461Y-13172D01*
X638861Y-13239D01*
X639261Y-13439D01*
G01X642061Y-15372D02*
X642394Y-15639D01*
X642861Y-15839D01*
X643261D01*
X643661Y-15706D01*
X643928Y-15506D01*
X644061Y-15239D01*
X643994Y-14839D01*
X643728Y-14639D01*
X642528Y-14239D01*
X642261Y-13772D01*
X642394Y-13439D01*
X642661Y-13239D01*
X643061Y-13172D01*
X643461Y-13239D01*
X643861Y-13439D01*
G01X646794Y-14506D02*
X648528D01*
G01X651861Y-15839D02*
Y-12439D01*
X651994Y-12106D01*
X652261Y-11906D01*
X652661Y-11839D01*
X653061Y-11972D01*
X653261Y-12306D01*
G01X652461Y-13439D02*
X651128D01*
G01X656861Y-13172D02*
Y-15839D01*
G01Y-12106D02*
X656728Y-12039D01*
Y-11906D01*
X656861Y-11839D01*
X656994Y-11906D01*
Y-12039D01*
X656861Y-12106D01*
G01X661461Y-11839D02*
Y-15839D01*
G01X660528Y-13172D02*
X662394D01*
G01X669328Y-15839D02*
Y-11839D01*
X670928D01*
X671461Y-12039D01*
X671861Y-12506D01*
X671994Y-13039D01*
X671861Y-13572D01*
X671528Y-13972D01*
X670928Y-14172D01*
X669328D01*
G01X675261Y-11839D02*
Y-15839D01*
G01X673728Y-11839D02*
X676794D01*
G01X678461Y-15839D02*
Y-11839D01*
G01X681261D02*
Y-15839D01*
G01Y-13839D02*
X678461D01*
G01X687928Y-15839D02*
Y-11839D01*
G01X690061Y-13172D02*
X687928Y-14706D01*
G01X688794Y-14106D02*
X690194Y-15839D01*
G01X692661Y-14039D02*
X694794D01*
X694594Y-13572D01*
X694261Y-13306D01*
X693794Y-13172D01*
X693328Y-13239D01*
X692928Y-13439D01*
X692661Y-13906D01*
X692528Y-14306D01*
Y-14706D01*
X692661Y-15106D01*
X692994Y-15506D01*
X693394Y-15772D01*
X693861Y-15839D01*
X694328Y-15706D01*
X694794Y-15306D01*
G01X697261Y-14039D02*
X699394D01*
X699194Y-13572D01*
X698861Y-13306D01*
X698394Y-13172D01*
X697928Y-13239D01*
X697528Y-13439D01*
X697261Y-13906D01*
X697128Y-14306D01*
Y-14706D01*
X697261Y-15106D01*
X697594Y-15506D01*
X697994Y-15772D01*
X698461Y-15839D01*
X698928Y-15706D01*
X699394Y-15306D01*
G01X701661Y-17172D02*
Y-13172D01*
G01Y-13772D02*
X701994Y-13439D01*
X702328Y-13239D01*
X702861Y-13172D01*
X703328Y-13239D01*
X703794Y-13572D01*
X703994Y-14039D01*
X704061Y-14506D01*
X703994Y-14972D01*
X703794Y-15439D01*
X703394Y-15706D01*
X702861Y-15839D01*
X702394Y-15772D01*
X701928Y-15572D01*
X701661Y-15306D01*
G01X710928Y-15839D02*
Y-11839D01*
G01Y-13772D02*
X711261Y-13439D01*
X711594Y-13239D01*
X712128Y-13172D01*
X712528Y-13239D01*
X712994Y-13506D01*
X713194Y-13906D01*
Y-15839D01*
G01X716661D02*
X716261Y-15772D01*
X715861Y-15506D01*
X715594Y-15039D01*
X715461Y-14506D01*
X715594Y-13972D01*
X715861Y-13506D01*
X716261Y-13239D01*
X716661Y-13172D01*
X717061Y-13239D01*
X717461Y-13506D01*
X717728Y-13972D01*
X717794Y-14506D01*
X717728Y-15039D01*
X717461Y-15506D01*
X717061Y-15772D01*
X716661Y-15839D01*
G01X721261D02*
Y-11839D01*
G01X724861Y-14039D02*
X726994D01*
X726794Y-13572D01*
X726461Y-13306D01*
X725994Y-13172D01*
X725528Y-13239D01*
X725128Y-13439D01*
X724861Y-13906D01*
X724728Y-14306D01*
Y-14706D01*
X724861Y-15106D01*
X725194Y-15506D01*
X725594Y-15772D01*
X726061Y-15839D01*
X726528Y-15706D01*
X726994Y-15306D01*
G01X734061Y-15372D02*
X734394Y-15639D01*
X734861Y-15839D01*
X735261D01*
X735661Y-15706D01*
X735928Y-15506D01*
X736061Y-15239D01*
X735994Y-14839D01*
X735728Y-14639D01*
X734528Y-14239D01*
X734261Y-13772D01*
X734394Y-13439D01*
X734661Y-13239D01*
X735061Y-13172D01*
X735461Y-13239D01*
X735861Y-13439D01*
G01X739661Y-13172D02*
Y-15839D01*
G01Y-12106D02*
X739528Y-12039D01*
Y-11906D01*
X739661Y-11839D01*
X739794Y-11906D01*
Y-12039D01*
X739661Y-12106D01*
G01X743261Y-13172D02*
X745261D01*
X743261Y-15839D01*
X745261D01*
G01X747861Y-14039D02*
X749994D01*
X749794Y-13572D01*
X749461Y-13306D01*
X748994Y-13172D01*
X748528Y-13239D01*
X748128Y-13439D01*
X747861Y-13906D01*
X747728Y-14306D01*
Y-14706D01*
X747861Y-15106D01*
X748194Y-15506D01*
X748594Y-15772D01*
X749061Y-15839D01*
X749528Y-15706D01*
X749994Y-15306D01*
G01X758061Y-11839D02*
Y-15839D01*
G01X757128Y-13172D02*
X758994D01*
G01X762661Y-15839D02*
X762261Y-15772D01*
X761861Y-15506D01*
X761594Y-15039D01*
X761461Y-14506D01*
X761594Y-13972D01*
X761861Y-13506D01*
X762261Y-13239D01*
X762661Y-13172D01*
X763061Y-13239D01*
X763461Y-13506D01*
X763728Y-13972D01*
X763794Y-14506D01*
X763728Y-15039D01*
X763461Y-15506D01*
X763061Y-15772D01*
X762661Y-15839D01*
G01X767261D02*
Y-11839D01*
G01X770861Y-14039D02*
X772994D01*
X772794Y-13572D01*
X772461Y-13306D01*
X771994Y-13172D01*
X771528Y-13239D01*
X771128Y-13439D01*
X770861Y-13906D01*
X770728Y-14306D01*
Y-14706D01*
X770861Y-15106D01*
X771194Y-15506D01*
X771594Y-15772D01*
X772061Y-15839D01*
X772528Y-15706D01*
X772994Y-15306D01*
G01X775528Y-15839D02*
Y-13172D01*
G01Y-13706D02*
X775861Y-13439D01*
X776194Y-13239D01*
X776661Y-13172D01*
X776994Y-13239D01*
X777394Y-13439D01*
G01X782261Y-15839D02*
Y-13172D01*
G01Y-13639D02*
X781994Y-13372D01*
X781594Y-13239D01*
X781128Y-13172D01*
X780661Y-13306D01*
X780261Y-13572D01*
X779994Y-13972D01*
X779861Y-14506D01*
X779994Y-15039D01*
X780261Y-15439D01*
X780661Y-15706D01*
X781128Y-15839D01*
X781594Y-15772D01*
X781994Y-15572D01*
X782261Y-15306D01*
G01X784528Y-15839D02*
Y-13172D01*
G01Y-13839D02*
X784794Y-13506D01*
X785194Y-13239D01*
X785728Y-13172D01*
X786194Y-13239D01*
X786594Y-13506D01*
X786794Y-13972D01*
Y-15839D01*
G01X791328Y-13506D02*
X790861Y-13239D01*
X790461Y-13172D01*
X789928Y-13306D01*
X789528Y-13572D01*
X789261Y-14039D01*
X789194Y-14506D01*
X789261Y-14972D01*
X789528Y-15372D01*
X789928Y-15706D01*
X790461Y-15839D01*
X790928Y-15706D01*
X791328Y-15439D01*
G01X793861Y-14039D02*
X795994D01*
X795794Y-13572D01*
X795461Y-13306D01*
X794994Y-13172D01*
X794528Y-13239D01*
X794128Y-13439D01*
X793861Y-13906D01*
X793728Y-14306D01*
Y-14706D01*
X793861Y-15106D01*
X794194Y-15506D01*
X794594Y-15772D01*
X795061Y-15839D01*
X795528Y-15706D01*
X795994Y-15306D01*
G01X803328Y-14506D02*
X804928D01*
G01X804061Y-13639D02*
Y-15372D01*
G01X807461Y-15972D02*
X809861Y-11839D01*
G01X812394Y-14506D02*
X814128D01*
G01X816594Y-12506D02*
X816994Y-12106D01*
X817461Y-11906D01*
X817994Y-11839D01*
X818661Y-11972D01*
X819128Y-12306D01*
X819261Y-12706D01*
X819194Y-13106D01*
X818928Y-13439D01*
X817594Y-14106D01*
X816994Y-14572D01*
X816594Y-15239D01*
X816461Y-15839D01*
X819261D01*
G01X825061D02*
Y-13172D01*
G01Y-13906D02*
X825261Y-13572D01*
X825594Y-13306D01*
X826061Y-13172D01*
X826528Y-13306D01*
X826861Y-13572D01*
X827061Y-13906D01*
Y-15839D01*
G01Y-13906D02*
X827261Y-13572D01*
X827594Y-13306D01*
X828061Y-13172D01*
X828528Y-13306D01*
X828861Y-13572D01*
X829061Y-13972D01*
Y-15839D01*
G01X831661Y-13172D02*
Y-15839D01*
G01Y-12106D02*
X831528Y-12039D01*
Y-11906D01*
X831661Y-11839D01*
X831794Y-11906D01*
Y-12039D01*
X831661Y-12106D01*
G01X836261Y-15839D02*
Y-11839D01*
G01X839861Y-15372D02*
X840194Y-15639D01*
X840661Y-15839D01*
X841061D01*
X841461Y-15706D01*
X841728Y-15506D01*
X841861Y-15239D01*
X841794Y-14839D01*
X841528Y-14639D01*
X840328Y-14239D01*
X840061Y-13772D01*
X840194Y-13439D01*
X840461Y-13239D01*
X840861Y-13172D01*
X841261Y-13239D01*
X841661Y-13439D01*
G01X628416Y0D02*
G03Y-7874I0J-3937D01*
G01X597707D02*
G03Y0I0J3937D01*
G01X780315Y-7874D02*
X628416D01*
G01X602362Y116141D02*
G03I-5906J0D01*
G01X736301Y-9511D02*
X736834Y-9844D01*
X737434Y-10044D01*
X737968D01*
X738501Y-9844D01*
X738901Y-9511D01*
X739101Y-9044D01*
X738968Y-8577D01*
X738634Y-8177D01*
X738034Y-7911D01*
X737234Y-7777D01*
X736768Y-7511D01*
X736568Y-7044D01*
X736701Y-6577D01*
X737034Y-6244D01*
X737501Y-6044D01*
X737968D01*
X738434Y-6177D01*
X738834Y-6511D01*
G01X742301Y-10044D02*
Y-6044D01*
G01X746901Y-7377D02*
Y-10044D01*
G01Y-6311D02*
X746768Y-6244D01*
Y-6111D01*
X746901Y-6044D01*
X747034Y-6111D01*
Y-6244D01*
X746901Y-6311D01*
G01X751501Y-6044D02*
Y-10044D01*
G01X750568Y-7377D02*
X752434D01*
G01X730261Y-11639D02*
X730251Y2871D01*
X735251Y-2129D01*
X725251D01*
X730251Y2871D01*
G01X744601Y-544D02*
X742601Y-2544D01*
X746601D01*
X744601Y-544D01*
Y-6544D01*
G01X702661Y0D02*
X765161D01*
G01X706161Y55650D02*
X760767D01*
Y3406D01*
X706161D01*
Y55650D01*
G01X817003Y-86834D02*
G03I-4292J0D01*
G01X811771Y-102362D02*
G03X826771Y-87362I0J15000D01*
G01X811023Y0D02*
G03Y-7874I0J-3937D01*
G01X780315D02*
G03Y0I0J3937D01*
G01X822834Y-7874D02*
X811023D01*
G01X818897Y0D02*
G03X826771Y7874I0J7874D01*
G01X818897Y0D02*
X807086D01*
G01X787401Y198819D02*
G03I-5905J0D01*
G01X792421Y499724D02*
G03I-3051J0D01*
G01X793504Y535157D02*
G03I-4134J0D01*
G01X796653Y517441D02*
G03I-7283J0D01*
G01X826771Y562992D02*
G03X818897Y570866I-7874J0D01*
G01X826771Y-11811D02*
Y-87362D01*
G01Y-11811D02*
G03X822834Y-7874I-3937J0D01*
G01X826771Y562992D02*
Y7874D01*
G54D13*
X38502Y161319D03*
X49302D03*
X43902D03*
X49302Y150519D03*
Y155919D03*
X43902Y150519D03*
Y155919D03*
X38502D03*
Y150519D03*
X108672Y138471D03*
Y132871D03*
X90672Y138471D03*
X102672D03*
X96672D03*
X84672D03*
Y132871D03*
X96672D03*
X102672D03*
X90672D03*
X1019575Y350603D03*
G54D22*
X276700Y66700D03*
X306292Y252825D03*
X302262Y262642D03*
X332000Y266336D03*
X337500Y266050D03*
X594200Y395200D03*
X604832Y395220D03*
X640144Y40969D03*
X775486Y287316D03*
X1019575Y519203D03*
G54D14*
X54900Y204700D03*
X49900Y209700D03*
X59900D03*
X54900Y214700D03*
Y209700D03*
X201400Y174400D03*
X192400D03*
X196900D03*
X179800Y133500D03*
X175800Y129500D03*
X179800D03*
X175800Y133500D03*
X192400Y191600D03*
X196900D03*
X201400D03*
X192400Y187300D03*
X196900D03*
X201400D03*
Y178700D03*
X192400Y183000D03*
X196900D03*
X201400D03*
X192400Y178700D03*
X196900D03*
X246493Y399567D03*
X242893D03*
X257020Y390670D03*
X253420D03*
X249820D03*
X246220D03*
X256120Y395170D03*
X243120D03*
X247620D03*
X251870D03*
X242620Y390670D03*
X260893Y399567D03*
X257293D03*
X260620Y390670D03*
Y395170D03*
X253693Y399567D03*
X250093D03*
X609400Y446850D03*
X604400Y456100D03*
Y451850D03*
Y447350D03*
Y460350D03*
X609400Y450450D03*
Y454050D03*
Y457650D03*
Y461250D03*
X599503Y447123D03*
Y450723D03*
Y454323D03*
Y457923D03*
X604400Y464850D03*
X609400D03*
X599503Y461523D03*
Y465123D03*
X694400Y452900D03*
Y457400D03*
Y461900D03*
X689900Y457400D03*
Y452950D03*
X689700Y461850D03*
X698900Y457400D03*
X699000Y452950D03*
X698950Y461800D03*
X1019575Y491103D03*
G54D23*
X295275Y531496D03*
X531495D03*
X1019575Y238203D03*
G54D24*
X388189Y48426D03*
X374016D03*
X359843D03*
X345670D03*
X388189Y34252D03*
X374016D03*
X359843D03*
X345670D03*
X388189Y20079D03*
X374016D03*
X359843D03*
X345670D03*
X388189Y44095D03*
X374016D03*
X359843D03*
X345670D03*
X388189Y38583D03*
X374016D03*
X359843D03*
X345670D03*
X388189Y29922D03*
X374016D03*
X359843D03*
X345670D03*
X388189Y24410D03*
X374016D03*
X359843D03*
X345670D03*
X388189Y15748D03*
X374016D03*
X359843D03*
X345670D03*
X388189Y10237D03*
X374016D03*
X359843D03*
X345670D03*
X388189Y5906D03*
X374016D03*
X359843D03*
X345670D03*
X381103Y38977D03*
X366929D03*
X352756D03*
X338583D03*
X381103Y24804D03*
X366929D03*
X352756D03*
X338583D03*
X381103Y53150D03*
X366929D03*
X352756D03*
X338583D03*
X381103Y48819D03*
X366929D03*
X352756D03*
X338583D03*
X381103Y43307D03*
X366929D03*
X352756D03*
X338583D03*
X381103Y34646D03*
X366929D03*
X352756D03*
X338583D03*
X381103Y29134D03*
X366929D03*
X352756D03*
X338583D03*
X381103Y20473D03*
X366929D03*
X352756D03*
X338583D03*
X381103Y14961D03*
X366929D03*
X352756D03*
X338583D03*
X444882Y48426D03*
X430709D03*
X416536D03*
X402363D03*
X444882Y34252D03*
X430709D03*
X416536D03*
X402363D03*
X444882Y20079D03*
X430709D03*
X416536D03*
X402363D03*
X444882Y44095D03*
X430709D03*
X416536D03*
X402363D03*
X444882Y38583D03*
X430709D03*
X416536D03*
X402363D03*
X444882Y29922D03*
X430709D03*
X416536D03*
X402363D03*
X444882Y24410D03*
X430709D03*
X416536D03*
X402363D03*
X444882Y15748D03*
X430709D03*
X416536D03*
X402363D03*
X444882Y10237D03*
X430709D03*
X416536D03*
X402363D03*
X444882Y5906D03*
X430709D03*
X416536D03*
X402363D03*
X437796Y38977D03*
X423622D03*
X409449D03*
X395276D03*
X437796Y24804D03*
X423622D03*
X409449D03*
X395276D03*
X437796Y53150D03*
X423622D03*
X409449D03*
X395276D03*
X437796Y48819D03*
X423622D03*
X409449D03*
X395276D03*
X437796Y43307D03*
X423622D03*
X409449D03*
X395276D03*
X437796Y34646D03*
X423622D03*
X409449D03*
X395276D03*
X437796Y29134D03*
X423622D03*
X409449D03*
X395276D03*
X437796Y20473D03*
X423622D03*
X409449D03*
X395276D03*
X437796Y14961D03*
X423622D03*
X409449D03*
X395276D03*
X501575Y48426D03*
X487402D03*
X473229D03*
X459055D03*
X501575Y34252D03*
X487402D03*
X473229D03*
X459055D03*
X501575Y20079D03*
X487402D03*
X473229D03*
X459055D03*
X501575Y44095D03*
X487402D03*
X473229D03*
X459055D03*
X501575Y38583D03*
X487402D03*
X473229D03*
X459055D03*
X501575Y29922D03*
X487402D03*
X473229D03*
X459055D03*
X501575Y24410D03*
X487402D03*
X473229D03*
X459055D03*
X501575Y15748D03*
X487402D03*
X473229D03*
X459055D03*
X501575Y10237D03*
X487402D03*
X473229D03*
X459055D03*
X501575Y5906D03*
X487402D03*
X473229D03*
X459055D03*
X508662Y38977D03*
X494489D03*
X480315D03*
X466142D03*
X451969D03*
X508662Y24804D03*
X494489D03*
X480315D03*
X466142D03*
X451969D03*
X508662Y53150D03*
X494489D03*
X480315D03*
X466142D03*
X451969D03*
X508662Y48819D03*
X494489D03*
X480315D03*
X466142D03*
X451969D03*
X508662Y43307D03*
X494489D03*
X480315D03*
X466142D03*
X451969D03*
X508662Y34646D03*
X494489D03*
X480315D03*
X466142D03*
X451969D03*
X508662Y29134D03*
X494489D03*
X480315D03*
X466142D03*
X451969D03*
X508662Y20473D03*
X494489D03*
X480315D03*
X466142D03*
X451969D03*
X508662Y14961D03*
X494489D03*
X480315D03*
X466142D03*
X451969D03*
X572441Y48426D03*
X558268D03*
X544095D03*
X529922D03*
X515748D03*
X572441Y34252D03*
X558268D03*
X544095D03*
X529922D03*
X515748D03*
X572441Y20079D03*
X558268D03*
X544095D03*
X529922D03*
X515748D03*
X572441Y44095D03*
X558268D03*
X544095D03*
X529922D03*
X515748D03*
X572441Y38583D03*
X558268D03*
X544095D03*
X529922D03*
X515748D03*
X572441Y29922D03*
X558268D03*
X544095D03*
X529922D03*
X515748D03*
X572441Y24410D03*
X558268D03*
X544095D03*
X529922D03*
X515748D03*
X572441Y15748D03*
X558268D03*
X544095D03*
X529922D03*
X515748D03*
X572441Y10237D03*
X558268D03*
X544095D03*
X529922D03*
X515748D03*
X572441Y5906D03*
X558268D03*
X544095D03*
X529922D03*
X515748D03*
X565355Y38977D03*
X551181D03*
X537008D03*
X522835D03*
X565355Y24804D03*
X551181D03*
X537008D03*
X522835D03*
X565355Y53150D03*
X551181D03*
X537008D03*
X522835D03*
X565355Y48819D03*
X551181D03*
X537008D03*
X522835D03*
X565355Y43307D03*
X551181D03*
X537008D03*
X522835D03*
X565355Y34646D03*
X551181D03*
X537008D03*
X522835D03*
X565355Y29134D03*
X551181D03*
X537008D03*
X522835D03*
X565355Y20473D03*
X551181D03*
X537008D03*
X522835D03*
X565355Y14961D03*
X551181D03*
X537008D03*
X522835D03*
X586614Y48426D03*
Y34252D03*
Y20079D03*
Y44095D03*
Y38583D03*
Y29922D03*
Y24410D03*
Y15748D03*
Y10237D03*
Y5906D03*
X579528Y38977D03*
Y24804D03*
Y53150D03*
Y48819D03*
Y43307D03*
Y34646D03*
Y29134D03*
Y20473D03*
Y14961D03*
X758267Y48426D03*
X744094D03*
X729921D03*
X715748D03*
X758267Y44095D03*
X744094D03*
X729921D03*
X715748D03*
X758267Y38583D03*
X744094D03*
X729921D03*
X715748D03*
X758267Y34252D03*
X744094D03*
X729921D03*
X715748D03*
X758267Y29922D03*
X744094D03*
X729921D03*
X715748D03*
X758267Y24410D03*
X744094D03*
X729921D03*
X715748D03*
X758267Y20079D03*
X744094D03*
X729921D03*
X715748D03*
X758267Y15748D03*
X744094D03*
X729921D03*
X715748D03*
X758267Y10237D03*
X744094D03*
X729921D03*
X715748D03*
X758267Y5906D03*
X744094D03*
X729921D03*
X715748D03*
X751181Y53150D03*
X737007D03*
X722834D03*
X708661D03*
X751181Y48819D03*
X737007D03*
X722834D03*
X708661D03*
X751181Y43307D03*
X737007D03*
X722834D03*
X708661D03*
X751181Y38977D03*
X737007D03*
X722834D03*
X708661D03*
X751181Y34646D03*
X737007D03*
X722834D03*
X708661D03*
X751181Y29134D03*
X737007D03*
X722834D03*
X708661D03*
X751181Y24804D03*
X737007D03*
X722834D03*
X708661D03*
X751181Y20473D03*
X737007D03*
X722834D03*
X708661D03*
X751181Y14961D03*
X737007D03*
X722834D03*
X708661D03*
X1019575Y434903D03*
G54D15*
X37402Y517441D03*
X789370D03*
X1019575Y210103D03*
G54D16*
X37402Y499724D03*
X789370D03*
X1019575Y294403D03*
G54D25*
X381103Y10651D03*
X366929D03*
X352756D03*
X338583D03*
X437796D03*
X423622D03*
X409449D03*
X395276D03*
X410236Y419291D03*
Y404331D03*
Y449212D03*
Y434252D03*
X508661Y10651D03*
X494488D03*
X480315D03*
X466142D03*
X451969D03*
X565354D03*
X551181D03*
X537008D03*
X522835D03*
X579527D03*
X751181D03*
X737007D03*
X722834D03*
X708661D03*
X1019575Y463003D03*
G54D26*
X374015Y156220D03*
X531496Y371299D03*
X596456Y116142D03*
X781496Y198818D03*
X1019575Y41503D03*
G54D17*
X37402Y535158D03*
X789370D03*
X1019575Y266303D03*
G54D18*
X116063Y14567D03*
X1019575Y97703D03*
G54D27*
X374432Y316002D03*
X425197Y236220D03*
X425196Y228347D03*
X433070Y236221D03*
X440944D03*
X448818D03*
X433070Y228347D03*
X440944D03*
X448818D03*
X405512Y212599D03*
X393701Y208662D03*
X401575D03*
X409449D03*
X417323D03*
X425197D03*
X433071D03*
X440945D03*
X448819D03*
X413386Y212599D03*
X421260D03*
X429134D03*
X437008D03*
X444882D03*
X421258Y232283D03*
X448818Y232284D03*
X440944D03*
X433070D03*
X433071Y224410D03*
X440945D03*
X448819D03*
X397638Y232284D03*
X389764Y204725D03*
Y220473D03*
Y208662D03*
Y228347D03*
X409449Y236221D03*
X393701Y228347D03*
Y216536D03*
Y212599D03*
X397638D03*
X401575D03*
X393701Y220473D03*
X397638Y200788D03*
X405512D03*
X413386D03*
X421260D03*
X429134D03*
X437008D03*
X444882D03*
X409449Y212599D03*
Y224410D03*
X417323Y212599D03*
X425197D03*
X433071D03*
X440945D03*
X448819D03*
X425197Y224410D03*
X417323D03*
X413386D03*
X409449Y232284D03*
X397638Y236221D03*
Y228347D03*
Y224410D03*
X389000Y236100D03*
X401575Y236221D03*
X405512D03*
X417322D03*
X409449Y220473D03*
Y216536D03*
X413386Y220473D03*
Y216536D03*
X417323Y220473D03*
Y216536D03*
X421260Y220473D03*
Y216536D03*
X425197Y220473D03*
Y216536D03*
X429134Y220473D03*
Y216536D03*
X433071Y220473D03*
Y216536D03*
X437008Y220473D03*
Y216536D03*
X440945Y220473D03*
Y216536D03*
X444882Y220473D03*
Y216536D03*
X448819Y220473D03*
Y216536D03*
X409449Y204725D03*
Y200788D03*
X413386Y208662D03*
Y204725D03*
X417323D03*
Y200788D03*
X421260Y208662D03*
Y204725D03*
X425197D03*
Y200788D03*
X429134Y208662D03*
Y204725D03*
X433071D03*
Y200788D03*
X437008Y208662D03*
Y204725D03*
X440945D03*
Y200788D03*
X444882Y208662D03*
Y204725D03*
X448819D03*
Y200788D03*
X389764Y216536D03*
Y212599D03*
X397638Y220473D03*
Y216536D03*
X401575Y220473D03*
Y216536D03*
X405512Y220473D03*
Y216536D03*
X393701Y204725D03*
Y200788D03*
X397638Y208662D03*
Y204725D03*
X401575D03*
Y200788D03*
X405512Y208662D03*
Y204725D03*
X401575Y232284D03*
X401727Y228641D03*
X405512Y232284D03*
X413386D03*
X405512Y228347D03*
X409449Y259843D03*
X425197Y291339D03*
X433071Y295276D03*
Y299213D03*
Y291339D03*
X448819Y287403D03*
X448818Y291339D03*
Y295276D03*
X437008Y299213D03*
Y291339D03*
X448818Y299214D03*
X425196Y283466D03*
X433070Y279528D03*
X433071Y275591D03*
X433070Y255905D03*
X437057Y279414D03*
X397638Y240158D03*
Y295276D03*
X405512D03*
X397638Y271654D03*
X409449Y267717D03*
X397638Y287402D03*
X405512D03*
X397638Y279528D03*
X409449Y275591D03*
X397638Y259843D03*
X405512D03*
Y255906D03*
X389764Y251969D03*
X393701D03*
X397638D03*
X409449Y244095D03*
Y255906D03*
X417323Y299213D03*
X421260Y291339D03*
X425197Y259843D03*
X417323Y267717D03*
X429134Y271654D03*
X417323Y275591D03*
X429134Y248032D03*
X425197Y255906D03*
X417323D03*
X413386Y259843D03*
X429134Y279528D03*
X421260D03*
X433071Y240158D03*
Y248032D03*
X448819Y240158D03*
X440945D03*
X444882Y279529D03*
X448819Y248032D03*
X440945D03*
X448818Y259843D03*
Y267718D03*
X440944D03*
X433071Y263781D03*
X440944Y259843D03*
X429134Y295277D03*
Y299214D03*
X437007Y287402D03*
X429134Y291340D03*
X437008Y275591D03*
X444882D03*
X437007Y267718D03*
X448818Y255906D03*
Y263780D03*
Y271655D03*
X440944Y263780D03*
Y271655D03*
X437007Y259843D03*
Y255905D03*
X440944Y255906D03*
X421260Y259843D03*
X429134Y263781D03*
Y255906D03*
X433071Y283465D03*
X425197Y287402D03*
X444882D03*
X440945Y283465D03*
X448819D03*
X444882Y299213D03*
X425196Y240158D03*
X409449D03*
Y248032D03*
X397638Y244095D03*
X421260Y255906D03*
X425197Y299213D03*
X429134Y287403D03*
X417323Y259843D03*
X413386Y255906D03*
X440945Y295276D03*
Y299213D03*
Y291339D03*
Y287402D03*
X437008Y295276D03*
X429134Y251969D03*
X417323D03*
X413386Y248032D03*
X405512D03*
X421260Y251969D03*
X405512Y244095D03*
X401575D03*
X413386D03*
X417323Y248032D03*
X401575Y240158D03*
X405512D03*
X433070Y287402D03*
X413387Y240158D03*
X421260Y248032D03*
X417323Y244095D03*
X413386Y251969D03*
X401575Y248032D03*
X421260Y295277D03*
X448819Y244095D03*
X440945D03*
X433071D03*
X421259Y240158D03*
X421260Y244095D03*
X417323Y240157D03*
X421260Y299214D03*
X425197Y295276D03*
X413386Y311025D03*
X425197Y318898D03*
Y303150D03*
X429134Y314961D03*
Y311024D03*
X448819Y307088D03*
X448818Y311024D03*
Y303151D03*
X444882Y314961D03*
Y318898D03*
X433071Y314961D03*
X431102Y331263D03*
X397638Y326772D03*
X409449D03*
X397638Y318898D03*
X409449D03*
Y314961D03*
X397638Y311024D03*
X409449D03*
X417323Y326772D03*
Y318898D03*
X425197Y311024D03*
X433071D03*
X397638Y303150D03*
X405512D03*
X413386Y307087D03*
X440945Y318898D03*
X448819D03*
X417323Y307087D03*
Y303150D03*
X429134Y303151D03*
X425197Y314961D03*
X413386Y326772D03*
X425197Y307087D03*
X417323Y314961D03*
X433071Y307087D03*
X448819Y314961D03*
X440945D03*
X417323Y311024D03*
X429134Y318898D03*
X442800Y330300D03*
X446200Y327400D03*
X440945Y303150D03*
Y311024D03*
Y307087D03*
X444881Y322835D03*
X442913Y327204D03*
X440944Y322835D03*
X438976Y327204D03*
X437008Y318898D03*
Y314961D03*
Y311024D03*
Y303150D03*
Y307087D03*
X433071Y318898D03*
X421260Y326772D03*
X421259Y322835D03*
X421260Y318898D03*
Y314961D03*
X417322Y322835D03*
X413386Y314962D03*
X421260Y307088D03*
X433071Y303150D03*
X421260Y303151D03*
X456693Y236221D03*
X464567D03*
X472441D03*
X460630Y208662D03*
X468504D03*
X484252D03*
X476378D03*
X496063D03*
X456693Y212599D03*
X464567D03*
X503937Y216536D03*
X472441Y212599D03*
X480315D03*
X488189D03*
X507874D03*
Y236221D03*
X503937Y232284D03*
X507874Y228347D03*
X503937Y224410D03*
X507874Y220473D03*
X472441Y228347D03*
X464567D03*
X456693D03*
X480315D03*
X484252Y236221D03*
X488189Y232284D03*
X456693D03*
X464567D03*
X472441D03*
X480315D03*
X456693Y200788D03*
X464567D03*
X492126Y208662D03*
Y204725D03*
X500000D03*
X472441Y200788D03*
X480315D03*
X488189D03*
X492126D03*
X460630Y212599D03*
X468504D03*
X492126Y216536D03*
X476378Y212599D03*
X484252D03*
X492126D03*
X503937D03*
X507874Y208662D03*
X503937Y204725D03*
X507874D03*
X503937Y236221D03*
Y228347D03*
X492126Y220473D03*
X503937D03*
X511811Y208662D03*
X507874Y200788D03*
X511811D03*
X472441Y224410D03*
X464567D03*
X456693D03*
X480315D03*
X492126D03*
X488189D03*
X492126Y232284D03*
Y236221D03*
X500000Y200788D03*
X503937D03*
X456693Y220473D03*
Y216536D03*
X460630Y220473D03*
Y216536D03*
X464567Y220473D03*
Y216536D03*
X468504Y220473D03*
Y216536D03*
X472441Y220473D03*
Y216536D03*
X476378Y220473D03*
Y216536D03*
X480315Y220473D03*
Y216536D03*
X484252Y220473D03*
Y216536D03*
X488189Y220473D03*
Y216536D03*
X500000Y208662D03*
X503937D03*
X496063Y212599D03*
X500000D03*
X496063Y216536D03*
X500000D03*
X496063Y220473D03*
X500000D03*
X496063Y224410D03*
X500000D03*
X496063Y228347D03*
X500000D03*
X496063Y232284D03*
X500000D03*
X496063Y236221D03*
X500000D03*
X456693Y208662D03*
Y204725D03*
X460630D03*
Y200788D03*
X464567Y208662D03*
Y204725D03*
X468504D03*
Y200788D03*
X472441Y208662D03*
Y204725D03*
X476378D03*
Y200788D03*
X480315Y208662D03*
Y204725D03*
X484252D03*
Y200788D03*
X488189Y208662D03*
Y204725D03*
X468504Y299214D03*
X472442Y287402D03*
X480315Y295276D03*
X484252Y295277D03*
X476378Y291339D03*
X452755Y287402D03*
Y291340D03*
Y295277D03*
X503937Y255906D03*
X507874Y251969D03*
X503937Y248032D03*
X507874Y244095D03*
X503937Y240158D03*
X507874Y271654D03*
X503937Y267717D03*
X507874Y259843D03*
Y287402D03*
X503937Y283465D03*
X507874Y279528D03*
X503937Y275591D03*
Y299213D03*
X507874Y295276D03*
X503937Y291339D03*
X492126Y287402D03*
X484252Y271654D03*
Y279528D03*
X488189Y267717D03*
Y275591D03*
X492126Y271654D03*
Y279528D03*
X488189Y283465D03*
X484252Y259843D03*
Y251969D03*
Y244095D03*
X492126Y259843D03*
Y251969D03*
Y244095D03*
X464567Y299214D03*
X456693Y279528D03*
Y267718D03*
X464567D03*
X472441Y295276D03*
X503937Y251969D03*
Y244095D03*
Y271654D03*
Y259843D03*
Y287402D03*
Y279528D03*
Y295276D03*
X488189Y287402D03*
X492126Y291339D03*
X488189D03*
X472441Y240158D03*
X456693Y259843D03*
X464567Y240158D03*
X456693D03*
X480315Y267717D03*
Y271654D03*
Y275591D03*
Y279528D03*
Y283465D03*
X492126Y267717D03*
X488189Y271654D03*
X492126Y275591D03*
X488189Y279528D03*
X492126Y283465D03*
X480315Y259843D03*
Y240158D03*
Y244095D03*
Y248032D03*
Y251969D03*
Y255906D03*
X488189Y259843D03*
X492126Y240158D03*
X488189D03*
X492126Y248032D03*
X488189D03*
Y255906D03*
X452757Y279529D03*
X464567D03*
X472441Y275591D03*
Y267717D03*
Y283465D03*
Y259843D03*
Y251969D03*
X456693Y248032D03*
X464567D03*
Y259843D03*
X472441Y291339D03*
X464568Y287402D03*
X460630Y275592D03*
X464568D03*
X452756D03*
X456693Y255906D03*
X464567D03*
Y263780D03*
X456693D03*
X464567Y271655D03*
X456693D03*
X476379Y287402D03*
X472441Y299213D03*
X480315D03*
X488189D03*
X456693Y287402D03*
X460630Y283465D03*
X468504D03*
X468505Y287402D03*
X460631Y295277D03*
X456693Y299213D03*
X460630D03*
X480316Y287403D03*
X484252Y291340D03*
Y287402D03*
X488189Y295276D03*
X456694D03*
X496063Y255906D03*
X500000D03*
X496063Y259843D03*
X500000D03*
X496063Y267717D03*
X500000D03*
X496063Y240158D03*
X500000D03*
X496063Y244095D03*
X500000D03*
X496063Y271654D03*
X500000D03*
X496063Y248032D03*
X500000D03*
X496063Y251969D03*
X500000D03*
X496063Y275591D03*
X500000D03*
X496063Y279528D03*
X500000D03*
X496063Y283465D03*
X500000D03*
X496063Y287402D03*
X500000D03*
X507874Y255906D03*
X511811D03*
Y259843D03*
X507874Y267717D03*
X511811D03*
X507874Y240158D03*
X511811D03*
Y244095D03*
Y271654D03*
X507874Y248032D03*
X511811D03*
Y251969D03*
X507874Y275591D03*
X511811D03*
Y279528D03*
X507874Y283465D03*
X511811D03*
Y287402D03*
X480315Y291339D03*
X496063Y299213D03*
X500000D03*
X496063Y291339D03*
X500000D03*
X496063Y295276D03*
X500000D03*
X476378Y267717D03*
Y275591D03*
Y259843D03*
Y251969D03*
X472441Y244095D03*
X464567D03*
X456693D03*
Y291339D03*
X460630D03*
X500001Y314961D03*
X503937Y318898D03*
X488189Y307087D03*
X492126Y311024D03*
X460630Y307087D03*
X456693D03*
X460630Y311024D03*
X462599Y327204D03*
X456693Y311024D03*
Y314961D03*
X452755Y307087D03*
Y303150D03*
X456693Y318898D03*
X507874Y303150D03*
X472441D03*
X460630Y318898D03*
X468504D03*
X456693Y303150D03*
X476378Y318898D03*
X484252D03*
X492126D03*
X500000D03*
X496063Y307087D03*
X480315Y303150D03*
X492126D03*
X507874Y318898D03*
Y307087D03*
X511811D03*
X503937Y303150D03*
X484252D03*
X496063Y318898D03*
X488189Y311024D03*
X484252Y307087D03*
Y314961D03*
X476378D03*
X468504D03*
X507874D03*
X492126D03*
X500000Y311025D03*
X460630Y314961D03*
X496063D03*
X476378Y311024D03*
X472441Y307087D03*
X488189Y303150D03*
X500000Y307088D03*
X503937Y311024D03*
X468504Y303151D03*
X460630Y303150D03*
X464567Y303151D03*
X503937Y307087D03*
X507874Y311024D03*
X464567Y307088D03*
X468505D03*
X472441Y314961D03*
X492126Y307087D03*
X496063Y311024D03*
X464567Y311025D03*
Y318898D03*
X472441D03*
X496063Y303150D03*
X500000D03*
X470473Y327204D03*
X468504Y311024D03*
X488189Y322835D03*
X517000Y226370D03*
Y218500D03*
Y234252D03*
X517500Y297218D03*
X518647Y288943D03*
X515748Y240158D03*
Y267717D03*
Y255906D03*
Y248032D03*
Y283465D03*
Y275591D03*
Y259843D03*
Y244095D03*
Y271654D03*
Y251969D03*
Y279528D03*
Y287402D03*
Y318898D03*
Y307087D03*
X516500Y313000D03*
X666928Y144880D03*
X682675Y132281D03*
X688974D03*
X660630Y122834D03*
X660629Y119685D03*
X663779Y122834D03*
Y119685D03*
X670079Y122835D03*
X670078Y119685D03*
X673229Y122835D03*
X673228Y119685D03*
X679528Y122835D03*
X679527Y119685D03*
X682678Y122835D03*
X682677Y119685D03*
X688977Y122835D03*
X688976Y119685D03*
X692126Y122835D03*
Y119686D03*
X1019575Y575403D03*
G54D19*
X116063Y39075D03*
X1019575Y69603D03*
G54D28*
X389764Y460630D03*
X437008D03*
X1019575Y125803D03*
G54D29*
X401575Y410039D03*
X410433D03*
X419292D03*
X404528Y412795D03*
X413386D03*
X422244D03*
X401575Y425000D03*
X410433D03*
X419292D03*
X407480Y422244D03*
X416339D03*
X425197D03*
X407480Y407284D03*
X416339D03*
X425197D03*
X404528Y427756D03*
X413386D03*
X422244D03*
X401575Y439961D03*
X410433D03*
X419292D03*
X404528Y442717D03*
X413386D03*
X422244D03*
X401575Y454921D03*
X410433D03*
X419292D03*
X404528Y457677D03*
X413386D03*
X422244D03*
X407480Y437205D03*
X416339D03*
X425197D03*
X407480Y452165D03*
X416339D03*
X425197D03*
X1019575Y406803D03*
M02*
